G04*
G04 #@! TF.GenerationSoftware,Altium Limited,Altium Designer,23.6.0 (18)*
G04*
G04 Layer_Color=65535*
%FSLAX44Y44*%
%MOMM*%
G71*
G04*
G04 #@! TF.SameCoordinates,59133E90-4310-4D8A-9E2C-91A8D2F69FBB*
G04*
G04*
G04 #@! TF.FilePolarity,Positive*
G04*
G01*
G75*
%ADD10C,0.7620*%
%ADD11C,0.2500*%
%ADD12C,0.2000*%
%ADD13C,0.2032*%
G36*
X203273Y27425D02*
X203194Y27378D01*
X203120Y27327D01*
X203046Y27267D01*
X202982Y27212D01*
X202926Y27157D01*
X202880Y27115D01*
X202866Y27096D01*
X202852Y27083D01*
X202847Y27078D01*
X202843Y27073D01*
X202764Y26976D01*
X202690Y26879D01*
X202626Y26787D01*
X202575Y26694D01*
X202529Y26616D01*
X202510Y26583D01*
X202496Y26556D01*
X202482Y26532D01*
X202478Y26514D01*
X202468Y26505D01*
Y26500D01*
X202089D01*
X202117Y26569D01*
X202150Y26639D01*
X202182Y26708D01*
X202214Y26773D01*
X202242Y26828D01*
X202265Y26874D01*
X202284Y26902D01*
X202288Y26907D01*
Y26911D01*
X202339Y26995D01*
X202390Y27069D01*
X202436Y27133D01*
X202478Y27184D01*
X202510Y27230D01*
X202538Y27258D01*
X202556Y27281D01*
X202561Y27286D01*
X200060D01*
Y27679D01*
X203273D01*
Y27425D01*
D02*
G37*
G36*
X153963Y31018D02*
X153884Y30971D01*
X153810Y30921D01*
X153736Y30861D01*
X153672Y30805D01*
X153616Y30749D01*
X153570Y30708D01*
X153556Y30689D01*
X153542Y30676D01*
X153538Y30671D01*
X153533Y30666D01*
X153454Y30569D01*
X153380Y30472D01*
X153316Y30380D01*
X153265Y30287D01*
X153218Y30209D01*
X153200Y30176D01*
X153186Y30149D01*
X153172Y30126D01*
X153168Y30107D01*
X153158Y30098D01*
Y30093D01*
X152779D01*
X152807Y30162D01*
X152839Y30232D01*
X152872Y30301D01*
X152904Y30366D01*
X152932Y30421D01*
X152955Y30468D01*
X152973Y30495D01*
X152978Y30500D01*
Y30505D01*
X153029Y30588D01*
X153080Y30662D01*
X153126Y30726D01*
X153168Y30777D01*
X153200Y30824D01*
X153228Y30851D01*
X153246Y30874D01*
X153251Y30879D01*
X150750D01*
Y31272D01*
X153963D01*
Y31018D01*
D02*
G37*
G36*
X151129Y27796D02*
X151208Y27851D01*
X151240Y27879D01*
X151272Y27902D01*
X151300Y27925D01*
X151319Y27943D01*
X151332Y27957D01*
X151337Y27962D01*
X151360Y27985D01*
X151383Y28013D01*
X151443Y28078D01*
X151513Y28152D01*
X151582Y28230D01*
X151642Y28304D01*
X151670Y28336D01*
X151698Y28364D01*
X151716Y28387D01*
X151730Y28406D01*
X151739Y28415D01*
X151744Y28420D01*
X151809Y28494D01*
X151869Y28568D01*
X151929Y28632D01*
X151980Y28692D01*
X152030Y28748D01*
X152077Y28794D01*
X152118Y28840D01*
X152155Y28877D01*
X152192Y28914D01*
X152220Y28942D01*
X152243Y28965D01*
X152266Y28988D01*
X152294Y29011D01*
X152303Y29021D01*
X152382Y29085D01*
X152451Y29141D01*
X152521Y29187D01*
X152576Y29224D01*
X152627Y29252D01*
X152664Y29270D01*
X152687Y29279D01*
X152696Y29284D01*
X152766Y29312D01*
X152835Y29330D01*
X152900Y29349D01*
X152955Y29358D01*
X153006Y29363D01*
X153043Y29367D01*
X153066D01*
X153075D01*
X153145Y29363D01*
X153209Y29353D01*
X153274Y29344D01*
X153329Y29326D01*
X153440Y29279D01*
X153528Y29233D01*
X153570Y29206D01*
X153602Y29182D01*
X153635Y29159D01*
X153658Y29136D01*
X153676Y29118D01*
X153695Y29109D01*
X153699Y29099D01*
X153704Y29095D01*
X153750Y29044D01*
X153792Y28988D01*
X153824Y28928D01*
X153852Y28868D01*
X153898Y28748D01*
X153931Y28628D01*
X153940Y28577D01*
X153949Y28526D01*
X153954Y28480D01*
X153958Y28443D01*
X153963Y28410D01*
Y28364D01*
X153958Y28281D01*
X153954Y28202D01*
X153940Y28128D01*
X153926Y28059D01*
X153907Y27994D01*
X153889Y27934D01*
X153866Y27879D01*
X153843Y27828D01*
X153820Y27782D01*
X153796Y27745D01*
X153778Y27712D01*
X153759Y27685D01*
X153745Y27661D01*
X153732Y27648D01*
X153727Y27638D01*
X153722Y27634D01*
X153676Y27587D01*
X153625Y27546D01*
X153570Y27504D01*
X153514Y27472D01*
X153404Y27417D01*
X153293Y27380D01*
X153242Y27366D01*
X153191Y27352D01*
X153149Y27343D01*
X153112Y27333D01*
X153080Y27329D01*
X153057D01*
X153043Y27324D01*
X153038D01*
X152997Y27726D01*
X153103Y27736D01*
X153195Y27754D01*
X153279Y27782D01*
X153343Y27814D01*
X153399Y27842D01*
X153436Y27870D01*
X153459Y27888D01*
X153468Y27897D01*
X153524Y27967D01*
X153565Y28041D01*
X153598Y28119D01*
X153616Y28189D01*
X153630Y28253D01*
X153635Y28309D01*
X153639Y28327D01*
Y28355D01*
X153635Y28452D01*
X153616Y28540D01*
X153588Y28614D01*
X153561Y28679D01*
X153528Y28729D01*
X153505Y28762D01*
X153487Y28785D01*
X153477Y28794D01*
X153413Y28850D01*
X153348Y28891D01*
X153283Y28923D01*
X153218Y28942D01*
X153168Y28956D01*
X153122Y28960D01*
X153094Y28965D01*
X153089D01*
X153084D01*
X153001Y28956D01*
X152913Y28937D01*
X152835Y28905D01*
X152761Y28873D01*
X152701Y28836D01*
X152650Y28803D01*
X152631Y28794D01*
X152618Y28785D01*
X152613Y28776D01*
X152608D01*
X152557Y28739D01*
X152507Y28692D01*
X152451Y28642D01*
X152396Y28586D01*
X152285Y28470D01*
X152174Y28355D01*
X152123Y28295D01*
X152077Y28244D01*
X152035Y28193D01*
X151998Y28152D01*
X151970Y28119D01*
X151947Y28091D01*
X151933Y28073D01*
X151929Y28068D01*
X151832Y27953D01*
X151739Y27846D01*
X151656Y27759D01*
X151587Y27689D01*
X151527Y27629D01*
X151485Y27587D01*
X151457Y27564D01*
X151453Y27555D01*
X151448D01*
X151369Y27490D01*
X151295Y27440D01*
X151222Y27393D01*
X151157Y27356D01*
X151101Y27329D01*
X151060Y27310D01*
X151032Y27301D01*
X151027Y27296D01*
X151023D01*
X150972Y27278D01*
X150926Y27269D01*
X150879Y27259D01*
X150838Y27255D01*
X150801Y27250D01*
X150773D01*
X150755D01*
X150750D01*
Y29372D01*
X151129D01*
Y27796D01*
D02*
G37*
G36*
X179161Y30412D02*
X179083Y30365D01*
X179009Y30315D01*
X178935Y30254D01*
X178870Y30199D01*
X178815Y30143D01*
X178768Y30102D01*
X178755Y30083D01*
X178741Y30069D01*
X178736Y30065D01*
X178731Y30060D01*
X178653Y29963D01*
X178579Y29866D01*
X178514Y29774D01*
X178463Y29681D01*
X178417Y29603D01*
X178398Y29570D01*
X178385Y29543D01*
X178371Y29519D01*
X178366Y29501D01*
X178357Y29492D01*
Y29487D01*
X177978D01*
X178006Y29556D01*
X178038Y29626D01*
X178070Y29695D01*
X178103Y29760D01*
X178130Y29815D01*
X178153Y29862D01*
X178172Y29889D01*
X178177Y29894D01*
Y29899D01*
X178228Y29982D01*
X178278Y30056D01*
X178325Y30120D01*
X178366Y30171D01*
X178398Y30217D01*
X178426Y30245D01*
X178445Y30268D01*
X178449Y30273D01*
X175948D01*
Y30666D01*
X179161D01*
Y30412D01*
D02*
G37*
G36*
Y27925D02*
X179083Y27878D01*
X179009Y27827D01*
X178935Y27767D01*
X178870Y27712D01*
X178815Y27656D01*
X178768Y27615D01*
X178755Y27596D01*
X178741Y27582D01*
X178736Y27578D01*
X178731Y27573D01*
X178653Y27476D01*
X178579Y27379D01*
X178514Y27287D01*
X178463Y27194D01*
X178417Y27116D01*
X178398Y27083D01*
X178385Y27055D01*
X178371Y27032D01*
X178366Y27014D01*
X178357Y27005D01*
Y27000D01*
X177978D01*
X178006Y27069D01*
X178038Y27139D01*
X178070Y27208D01*
X178103Y27273D01*
X178130Y27328D01*
X178153Y27374D01*
X178172Y27402D01*
X178177Y27407D01*
Y27411D01*
X178228Y27495D01*
X178278Y27569D01*
X178325Y27633D01*
X178366Y27684D01*
X178398Y27730D01*
X178426Y27758D01*
X178445Y27781D01*
X178449Y27786D01*
X175948D01*
Y28179D01*
X179161D01*
Y27925D01*
D02*
G37*
G36*
X15220Y32576D02*
X15299Y32567D01*
X15378Y32553D01*
X15447Y32535D01*
X15512Y32512D01*
X15576Y32489D01*
X15632Y32461D01*
X15683Y32438D01*
X15729Y32410D01*
X15771Y32382D01*
X15803Y32359D01*
X15835Y32336D01*
X15858Y32318D01*
X15872Y32304D01*
X15882Y32295D01*
X15886Y32290D01*
X15937Y32234D01*
X15983Y32179D01*
X16020Y32119D01*
X16053Y32059D01*
X16085Y31999D01*
X16108Y31939D01*
X16140Y31828D01*
X16154Y31777D01*
X16164Y31731D01*
X16168Y31689D01*
X16173Y31652D01*
X16177Y31624D01*
Y31523D01*
X16168Y31467D01*
X16145Y31356D01*
X16113Y31254D01*
X16076Y31162D01*
X16039Y31088D01*
X16020Y31056D01*
X16006Y31028D01*
X15992Y31005D01*
X15983Y30991D01*
X15979Y30982D01*
X15974Y30977D01*
X16838Y31148D01*
Y32429D01*
X17213D01*
Y30838D01*
X15567Y30529D01*
X15516Y30898D01*
X15567Y30931D01*
X15609Y30972D01*
X15650Y31009D01*
X15683Y31046D01*
X15706Y31083D01*
X15729Y31111D01*
X15738Y31130D01*
X15743Y31134D01*
X15771Y31194D01*
X15794Y31254D01*
X15807Y31310D01*
X15821Y31365D01*
X15826Y31412D01*
X15831Y31449D01*
Y31536D01*
X15821Y31592D01*
X15798Y31689D01*
X15766Y31772D01*
X15734Y31846D01*
X15697Y31902D01*
X15664Y31943D01*
X15641Y31966D01*
X15637Y31976D01*
X15632D01*
X15553Y32040D01*
X15470Y32087D01*
X15382Y32119D01*
X15294Y32142D01*
X15220Y32156D01*
X15188Y32160D01*
X15160D01*
X15137Y32165D01*
X15119D01*
X15109D01*
X15105D01*
X15040D01*
X14980Y32156D01*
X14864Y32133D01*
X14767Y32100D01*
X14689Y32068D01*
X14624Y32031D01*
X14573Y31999D01*
X14559Y31985D01*
X14546Y31976D01*
X14541Y31971D01*
X14536Y31966D01*
X14499Y31929D01*
X14467Y31892D01*
X14411Y31809D01*
X14375Y31731D01*
X14351Y31652D01*
X14333Y31587D01*
X14328Y31532D01*
X14324Y31513D01*
Y31486D01*
X14328Y31398D01*
X14347Y31319D01*
X14370Y31250D01*
X14398Y31194D01*
X14425Y31144D01*
X14448Y31107D01*
X14467Y31088D01*
X14471Y31079D01*
X14536Y31023D01*
X14606Y30977D01*
X14684Y30940D01*
X14754Y30912D01*
X14823Y30894D01*
X14874Y30880D01*
X14897Y30875D01*
X14911Y30871D01*
X14920D01*
X14925D01*
X14892Y30459D01*
X14818Y30468D01*
X14749Y30482D01*
X14619Y30524D01*
X14509Y30575D01*
X14458Y30603D01*
X14416Y30630D01*
X14375Y30654D01*
X14338Y30681D01*
X14310Y30704D01*
X14287Y30727D01*
X14268Y30746D01*
X14250Y30755D01*
X14245Y30764D01*
X14240Y30769D01*
X14199Y30824D01*
X14162Y30880D01*
X14130Y30940D01*
X14102Y31000D01*
X14060Y31116D01*
X14032Y31231D01*
X14018Y31282D01*
X14014Y31333D01*
X14009Y31375D01*
X14005Y31412D01*
X14000Y31444D01*
Y31486D01*
X14005Y31583D01*
X14018Y31675D01*
X14037Y31763D01*
X14060Y31841D01*
X14093Y31916D01*
X14125Y31985D01*
X14157Y32050D01*
X14194Y32105D01*
X14231Y32156D01*
X14263Y32202D01*
X14301Y32239D01*
X14328Y32271D01*
X14351Y32295D01*
X14370Y32313D01*
X14384Y32322D01*
X14388Y32327D01*
X14448Y32373D01*
X14513Y32410D01*
X14573Y32447D01*
X14638Y32475D01*
X14763Y32521D01*
X14883Y32549D01*
X14934Y32558D01*
X14985Y32567D01*
X15026Y32572D01*
X15063Y32576D01*
X15096Y32581D01*
X15119D01*
X15133D01*
X15137D01*
X15220Y32576D01*
D02*
G37*
G36*
X17213Y28000D02*
X16834D01*
Y29567D01*
X16700Y29456D01*
X16556Y29350D01*
X16418Y29257D01*
X16284Y29169D01*
X16224Y29133D01*
X16168Y29100D01*
X16117Y29068D01*
X16076Y29045D01*
X16039Y29026D01*
X16016Y29012D01*
X15997Y29003D01*
X15992Y28998D01*
X15807Y28906D01*
X15623Y28823D01*
X15447Y28753D01*
X15368Y28726D01*
X15290Y28698D01*
X15220Y28670D01*
X15156Y28652D01*
X15100Y28633D01*
X15054Y28619D01*
X15012Y28606D01*
X14985Y28596D01*
X14966Y28592D01*
X14962D01*
X14772Y28545D01*
X14680Y28527D01*
X14596Y28513D01*
X14518Y28499D01*
X14439Y28485D01*
X14375Y28476D01*
X14310Y28467D01*
X14254Y28462D01*
X14203Y28458D01*
X14157Y28453D01*
X14120D01*
X14093Y28448D01*
X14074D01*
X14060D01*
X14056D01*
Y28851D01*
X14231Y28864D01*
X14393Y28888D01*
X14541Y28911D01*
X14610Y28925D01*
X14675Y28938D01*
X14730Y28948D01*
X14781Y28962D01*
X14828Y28971D01*
X14864Y28980D01*
X14892Y28989D01*
X14915Y28994D01*
X14929Y28998D01*
X14934D01*
X15146Y29068D01*
X15345Y29142D01*
X15442Y29179D01*
X15535Y29216D01*
X15618Y29257D01*
X15701Y29294D01*
X15775Y29327D01*
X15840Y29359D01*
X15895Y29387D01*
X15946Y29410D01*
X15988Y29433D01*
X16016Y29447D01*
X16034Y29456D01*
X16039Y29461D01*
X16136Y29516D01*
X16233Y29572D01*
X16321Y29627D01*
X16404Y29683D01*
X16478Y29734D01*
X16552Y29784D01*
X16616Y29835D01*
X16672Y29877D01*
X16727Y29918D01*
X16774Y29955D01*
X16811Y29992D01*
X16843Y30020D01*
X16871Y30039D01*
X16889Y30057D01*
X16898Y30066D01*
X16903Y30071D01*
X17213D01*
Y28000D01*
D02*
G37*
G36*
X158323Y43320D02*
X160455Y40428D01*
X159604D01*
X157873Y42884D01*
X157078Y42117D01*
Y40428D01*
X156431D01*
Y45297D01*
X157078D01*
Y42877D01*
X159484Y45297D01*
X160364D01*
X158323Y43320D01*
D02*
G37*
G36*
X166253Y40372D02*
Y40365D01*
X166246Y40344D01*
X166232Y40316D01*
X166217Y40280D01*
X166196Y40231D01*
X166175Y40175D01*
X166126Y40055D01*
X166077Y39922D01*
X166021Y39788D01*
X165964Y39668D01*
X165936Y39619D01*
X165915Y39570D01*
X165908Y39556D01*
X165887Y39521D01*
X165852Y39471D01*
X165809Y39408D01*
X165753Y39338D01*
X165690Y39267D01*
X165627Y39197D01*
X165549Y39141D01*
X165542Y39134D01*
X165514Y39120D01*
X165472Y39098D01*
X165408Y39070D01*
X165338Y39042D01*
X165254Y39021D01*
X165162Y39007D01*
X165057Y39000D01*
X165028D01*
X164993Y39007D01*
X164944D01*
X164888Y39021D01*
X164824Y39035D01*
X164754Y39049D01*
X164677Y39077D01*
X164613Y39633D01*
X164620D01*
X164648Y39626D01*
X164684Y39619D01*
X164726Y39605D01*
X164839Y39584D01*
X164951Y39577D01*
X164986D01*
X165021Y39584D01*
X165064D01*
X165169Y39605D01*
X165218Y39626D01*
X165268Y39647D01*
X165275D01*
X165289Y39661D01*
X165310Y39675D01*
X165338Y39697D01*
X165401Y39753D01*
X165458Y39830D01*
Y39837D01*
X165472Y39851D01*
X165486Y39880D01*
X165500Y39922D01*
X165528Y39978D01*
X165556Y40062D01*
X165598Y40161D01*
X165641Y40280D01*
Y40287D01*
X165655Y40316D01*
X165669Y40365D01*
X165697Y40428D01*
X164360Y43960D01*
X164993D01*
X165732Y41913D01*
Y41906D01*
X165739Y41899D01*
X165746Y41878D01*
X165753Y41842D01*
X165767Y41807D01*
X165781Y41765D01*
X165816Y41667D01*
X165859Y41547D01*
X165901Y41406D01*
X165943Y41259D01*
X165985Y41097D01*
Y41104D01*
X165992Y41118D01*
X165999Y41139D01*
X166006Y41167D01*
X166014Y41202D01*
X166028Y41244D01*
X166056Y41350D01*
X166091Y41470D01*
X166140Y41610D01*
X166182Y41751D01*
X166239Y41899D01*
X166999Y43960D01*
X167596D01*
X166253Y40372D01*
D02*
G37*
G36*
X151963Y45290D02*
X152019D01*
X152146Y45276D01*
X152287Y45262D01*
X152434Y45234D01*
X152582Y45198D01*
X152716Y45149D01*
X152723D01*
X152730Y45142D01*
X152772Y45121D01*
X152835Y45086D01*
X152906Y45037D01*
X152990Y44973D01*
X153082Y44896D01*
X153166Y44798D01*
X153244Y44692D01*
X153251Y44678D01*
X153272Y44636D01*
X153307Y44579D01*
X153342Y44495D01*
X153377Y44397D01*
X153412Y44291D01*
X153434Y44171D01*
X153441Y44052D01*
Y44038D01*
Y44002D01*
X153434Y43939D01*
X153419Y43862D01*
X153398Y43770D01*
X153363Y43672D01*
X153321Y43573D01*
X153265Y43468D01*
X153258Y43454D01*
X153237Y43425D01*
X153194Y43369D01*
X153138Y43313D01*
X153068Y43243D01*
X152983Y43165D01*
X152878Y43095D01*
X152758Y43025D01*
X152765D01*
X152779Y43017D01*
X152800Y43010D01*
X152828Y42996D01*
X152913Y42968D01*
X153011Y42919D01*
X153117Y42856D01*
X153237Y42778D01*
X153342Y42687D01*
X153441Y42574D01*
X153448Y42560D01*
X153476Y42518D01*
X153518Y42455D01*
X153560Y42370D01*
X153602Y42258D01*
X153645Y42138D01*
X153673Y41997D01*
X153680Y41842D01*
Y41835D01*
Y41828D01*
Y41786D01*
X153673Y41716D01*
X153659Y41631D01*
X153645Y41533D01*
X153616Y41427D01*
X153581Y41315D01*
X153532Y41202D01*
X153525Y41188D01*
X153504Y41153D01*
X153476Y41104D01*
X153434Y41033D01*
X153377Y40963D01*
X153321Y40886D01*
X153251Y40808D01*
X153173Y40745D01*
X153166Y40738D01*
X153138Y40717D01*
X153089Y40689D01*
X153025Y40660D01*
X152948Y40618D01*
X152857Y40576D01*
X152758Y40541D01*
X152638Y40506D01*
X152624D01*
X152582Y40492D01*
X152512Y40485D01*
X152420Y40470D01*
X152308Y40456D01*
X152174Y40442D01*
X152026Y40435D01*
X151858Y40428D01*
X150000D01*
Y45297D01*
X151914D01*
X151963Y45290D01*
D02*
G37*
G36*
X162481Y44031D02*
X162538Y44024D01*
X162608Y44009D01*
X162686Y43995D01*
X162777Y43974D01*
X162861Y43953D01*
X162960Y43918D01*
X163051Y43883D01*
X163150Y43834D01*
X163248Y43777D01*
X163347Y43714D01*
X163438Y43637D01*
X163523Y43552D01*
X163530Y43545D01*
X163544Y43531D01*
X163565Y43503D01*
X163593Y43461D01*
X163628Y43411D01*
X163664Y43355D01*
X163706Y43285D01*
X163748Y43200D01*
X163790Y43109D01*
X163832Y43010D01*
X163868Y42898D01*
X163903Y42778D01*
X163931Y42645D01*
X163952Y42504D01*
X163966Y42356D01*
X163973Y42194D01*
Y42187D01*
Y42159D01*
Y42110D01*
X163966Y42039D01*
X161328D01*
Y42032D01*
Y42011D01*
X161335Y41983D01*
Y41941D01*
X161342Y41892D01*
X161356Y41835D01*
X161377Y41709D01*
X161419Y41568D01*
X161475Y41413D01*
X161553Y41273D01*
X161651Y41146D01*
X161658D01*
X161665Y41132D01*
X161708Y41097D01*
X161771Y41047D01*
X161855Y40998D01*
X161968Y40942D01*
X162094Y40893D01*
X162235Y40857D01*
X162313Y40850D01*
X162397Y40843D01*
X162453D01*
X162517Y40850D01*
X162594Y40865D01*
X162679Y40886D01*
X162777Y40914D01*
X162868Y40956D01*
X162960Y41012D01*
X162967Y41019D01*
X163002Y41047D01*
X163044Y41090D01*
X163094Y41146D01*
X163150Y41223D01*
X163213Y41322D01*
X163277Y41434D01*
X163333Y41568D01*
X163952Y41491D01*
Y41484D01*
X163945Y41470D01*
X163938Y41441D01*
X163924Y41399D01*
X163903Y41357D01*
X163882Y41301D01*
X163825Y41181D01*
X163755Y41047D01*
X163657Y40907D01*
X163544Y40773D01*
X163403Y40646D01*
X163396D01*
X163382Y40632D01*
X163361Y40618D01*
X163333Y40597D01*
X163291Y40576D01*
X163248Y40555D01*
X163192Y40527D01*
X163129Y40499D01*
X163058Y40470D01*
X162988Y40442D01*
X162812Y40400D01*
X162615Y40365D01*
X162397Y40351D01*
X162320D01*
X162270Y40358D01*
X162207Y40365D01*
X162130Y40379D01*
X162045Y40393D01*
X161954Y40407D01*
X161757Y40463D01*
X161651Y40506D01*
X161553Y40548D01*
X161447Y40604D01*
X161349Y40668D01*
X161257Y40738D01*
X161166Y40822D01*
X161159Y40829D01*
X161145Y40843D01*
X161124Y40872D01*
X161096Y40914D01*
X161060Y40963D01*
X161025Y41019D01*
X160983Y41090D01*
X160941Y41167D01*
X160898Y41259D01*
X160856Y41357D01*
X160821Y41470D01*
X160786Y41589D01*
X160758Y41716D01*
X160737Y41856D01*
X160723Y42004D01*
X160716Y42159D01*
Y42166D01*
Y42201D01*
Y42243D01*
X160723Y42307D01*
X160730Y42384D01*
X160737Y42469D01*
X160751Y42567D01*
X160772Y42666D01*
X160828Y42891D01*
X160863Y43003D01*
X160905Y43123D01*
X160962Y43236D01*
X161025Y43341D01*
X161096Y43447D01*
X161173Y43545D01*
X161180Y43552D01*
X161194Y43566D01*
X161222Y43587D01*
X161257Y43622D01*
X161299Y43658D01*
X161356Y43700D01*
X161419Y43749D01*
X161497Y43791D01*
X161574Y43841D01*
X161665Y43883D01*
X161764Y43925D01*
X161869Y43960D01*
X161982Y43995D01*
X162102Y44016D01*
X162228Y44031D01*
X162362Y44038D01*
X162432D01*
X162481Y44031D01*
D02*
G37*
G36*
X116256Y52885D02*
X112609D01*
Y54063D01*
X116256D01*
Y52885D01*
D02*
G37*
G36*
X73153Y50000D02*
X71933D01*
Y58030D01*
X69131Y50000D01*
X67994D01*
X65220Y58169D01*
Y50000D01*
X64000D01*
Y59597D01*
X65900D01*
X68174Y52787D01*
Y52774D01*
X68188Y52746D01*
X68202Y52704D01*
X68230Y52635D01*
X68285Y52469D01*
X68355Y52261D01*
X68424Y52025D01*
X68507Y51789D01*
X68577Y51567D01*
X68632Y51373D01*
X68646Y51401D01*
X68660Y51470D01*
X68701Y51595D01*
X68757Y51761D01*
X68826Y51983D01*
X68923Y52247D01*
X69020Y52552D01*
X69145Y52912D01*
X71447Y59597D01*
X73153D01*
Y50000D01*
D02*
G37*
G36*
X149332Y50000D02*
X148001D01*
X144284Y59597D01*
X145671D01*
X148167Y52621D01*
Y52607D01*
X148181Y52579D01*
X148195Y52538D01*
X148223Y52483D01*
X148237Y52399D01*
X148264Y52316D01*
X148334Y52108D01*
X148417Y51872D01*
X148500Y51609D01*
X148667Y51054D01*
Y51068D01*
X148680Y51096D01*
X148694Y51137D01*
X148708Y51193D01*
X148750Y51345D01*
X148819Y51553D01*
X148889Y51789D01*
X148972Y52053D01*
X149069Y52330D01*
X149180Y52621D01*
X151787Y59597D01*
X153077D01*
X149332Y50000D01*
D02*
G37*
G36*
X128585Y59625D02*
X128654D01*
X128752Y59611D01*
X128987Y59569D01*
X129251Y59514D01*
X129542Y59417D01*
X129833Y59292D01*
X130125Y59125D01*
X130138D01*
X130152Y59098D01*
X130194Y59070D01*
X130249Y59028D01*
X130388Y58917D01*
X130568Y58765D01*
X130749Y58557D01*
X130957Y58307D01*
X131137Y58016D01*
X131303Y57683D01*
Y57669D01*
X131317Y57642D01*
X131345Y57586D01*
X131373Y57517D01*
X131400Y57420D01*
X131442Y57295D01*
X131470Y57156D01*
X131511Y57003D01*
X131553Y56823D01*
X131595Y56615D01*
X131622Y56393D01*
X131650Y56158D01*
X131678Y55894D01*
X131706Y55617D01*
X131719Y55312D01*
Y54993D01*
Y54979D01*
Y54909D01*
Y54812D01*
Y54688D01*
X131706Y54535D01*
Y54355D01*
X131692Y54147D01*
X131664Y53939D01*
X131622Y53467D01*
X131553Y52968D01*
X131456Y52496D01*
X131387Y52261D01*
X131317Y52052D01*
Y52039D01*
X131303Y52011D01*
X131276Y51955D01*
X131248Y51872D01*
X131206Y51789D01*
X131151Y51678D01*
X131012Y51442D01*
X130846Y51179D01*
X130652Y50901D01*
X130402Y50638D01*
X130125Y50402D01*
X130111D01*
X130083Y50374D01*
X130041Y50347D01*
X129986Y50319D01*
X129903Y50277D01*
X129819Y50222D01*
X129708Y50166D01*
X129598Y50125D01*
X129334Y50014D01*
X129015Y49917D01*
X128668Y49861D01*
X128280Y49834D01*
X128169D01*
X128100Y49847D01*
X128003D01*
X127892Y49861D01*
X127628Y49917D01*
X127337Y49986D01*
X127032Y50097D01*
X126727Y50250D01*
X126574Y50347D01*
X126435Y50458D01*
X126422Y50472D01*
X126408Y50485D01*
X126366Y50527D01*
X126325Y50569D01*
X126269Y50638D01*
X126200Y50721D01*
X126061Y50915D01*
X125922Y51165D01*
X125784Y51470D01*
X125673Y51817D01*
X125590Y52219D01*
X126727Y52316D01*
Y52302D01*
X126741Y52274D01*
Y52247D01*
X126755Y52191D01*
X126796Y52039D01*
X126852Y51872D01*
X126921Y51678D01*
X127018Y51484D01*
X127129Y51304D01*
X127268Y51151D01*
X127282Y51137D01*
X127337Y51096D01*
X127434Y51040D01*
X127545Y50985D01*
X127698Y50915D01*
X127878Y50860D01*
X128086Y50818D01*
X128308Y50804D01*
X128405D01*
X128502Y50818D01*
X128627Y50832D01*
X128779Y50860D01*
X128932Y50901D01*
X129098Y50957D01*
X129251Y51040D01*
X129265Y51054D01*
X129320Y51082D01*
X129403Y51137D01*
X129487Y51220D01*
X129598Y51318D01*
X129708Y51428D01*
X129819Y51553D01*
X129930Y51706D01*
X129944Y51720D01*
X129972Y51789D01*
X130028Y51886D01*
X130083Y52011D01*
X130152Y52177D01*
X130222Y52372D01*
X130291Y52593D01*
X130360Y52843D01*
Y52857D01*
X130374Y52871D01*
Y52912D01*
X130388Y52968D01*
X130416Y53106D01*
X130457Y53287D01*
X130485Y53509D01*
X130513Y53745D01*
X130527Y54008D01*
X130541Y54285D01*
Y54299D01*
Y54341D01*
Y54410D01*
Y54521D01*
X130527Y54493D01*
X130471Y54424D01*
X130388Y54327D01*
X130291Y54188D01*
X130152Y54050D01*
X129986Y53897D01*
X129792Y53745D01*
X129570Y53606D01*
X129542Y53592D01*
X129459Y53550D01*
X129334Y53495D01*
X129181Y53439D01*
X128974Y53370D01*
X128752Y53314D01*
X128502Y53273D01*
X128238Y53259D01*
X128127D01*
X128044Y53273D01*
X127933Y53287D01*
X127822Y53301D01*
X127684Y53328D01*
X127545Y53370D01*
X127226Y53467D01*
X127060Y53536D01*
X126893Y53620D01*
X126713Y53717D01*
X126546Y53842D01*
X126380Y53966D01*
X126228Y54119D01*
X126214Y54133D01*
X126186Y54160D01*
X126158Y54202D01*
X126103Y54271D01*
X126033Y54369D01*
X125964Y54466D01*
X125895Y54590D01*
X125825Y54729D01*
X125742Y54882D01*
X125673Y55048D01*
X125603Y55242D01*
X125534Y55436D01*
X125479Y55658D01*
X125451Y55894D01*
X125423Y56130D01*
X125409Y56393D01*
Y56407D01*
Y56463D01*
Y56532D01*
X125423Y56629D01*
X125437Y56754D01*
X125451Y56906D01*
X125479Y57059D01*
X125520Y57239D01*
X125617Y57600D01*
X125687Y57794D01*
X125770Y58002D01*
X125867Y58196D01*
X125992Y58376D01*
X126117Y58571D01*
X126269Y58737D01*
X126283Y58751D01*
X126311Y58779D01*
X126352Y58820D01*
X126422Y58876D01*
X126505Y58945D01*
X126616Y59028D01*
X126727Y59098D01*
X126866Y59195D01*
X127004Y59278D01*
X127171Y59347D01*
X127545Y59500D01*
X127739Y59555D01*
X127961Y59597D01*
X128183Y59625D01*
X128419Y59639D01*
X128516D01*
X128585Y59625D01*
D02*
G37*
G36*
X158180Y50000D02*
X157001D01*
Y57503D01*
X156988Y57489D01*
X156918Y57434D01*
X156835Y57350D01*
X156696Y57253D01*
X156544Y57128D01*
X156350Y56990D01*
X156128Y56837D01*
X155878Y56685D01*
X155864D01*
X155850Y56671D01*
X155767Y56615D01*
X155628Y56546D01*
X155462Y56463D01*
X155268Y56366D01*
X155060Y56269D01*
X154852Y56171D01*
X154644Y56088D01*
Y57225D01*
X154658D01*
X154685Y57253D01*
X154741Y57267D01*
X154810Y57309D01*
X154894Y57350D01*
X154991Y57406D01*
X155226Y57544D01*
X155504Y57697D01*
X155781Y57891D01*
X156072Y58113D01*
X156363Y58349D01*
X156377Y58363D01*
X156391Y58376D01*
X156433Y58418D01*
X156488Y58460D01*
X156613Y58598D01*
X156780Y58765D01*
X156946Y58959D01*
X157126Y59181D01*
X157279Y59403D01*
X157417Y59639D01*
X158180D01*
Y50000D01*
D02*
G37*
G36*
X140235Y58460D02*
X137073D01*
Y50000D01*
X135797Y50000D01*
Y58460D01*
X132635D01*
Y59597D01*
X140235Y59597D01*
Y58460D01*
D02*
G37*
G36*
X124244Y58460D02*
X119030D01*
Y55492D01*
X123537D01*
Y54355D01*
X119030D01*
Y50000D01*
X117754D01*
Y59597D01*
X124244D01*
Y58460D01*
D02*
G37*
G36*
X107491Y59583D02*
X107769Y59569D01*
X108046Y59542D01*
X108323Y59500D01*
X108559Y59458D01*
X108573D01*
X108601Y59444D01*
X108642D01*
X108698Y59417D01*
X108850Y59375D01*
X109045Y59306D01*
X109267Y59209D01*
X109502Y59084D01*
X109738Y58945D01*
X109960Y58765D01*
X109974Y58751D01*
X109988Y58737D01*
X110029Y58696D01*
X110085Y58654D01*
X110223Y58515D01*
X110390Y58321D01*
X110570Y58085D01*
X110764Y57808D01*
X110944Y57489D01*
X111097Y57128D01*
Y57115D01*
X111111Y57087D01*
X111139Y57031D01*
X111153Y56948D01*
X111194Y56851D01*
X111222Y56740D01*
X111250Y56615D01*
X111291Y56463D01*
X111333Y56310D01*
X111361Y56130D01*
X111430Y55742D01*
X111472Y55312D01*
X111485Y54840D01*
Y54826D01*
Y54798D01*
Y54729D01*
Y54660D01*
X111472Y54563D01*
Y54452D01*
X111458Y54188D01*
X111416Y53883D01*
X111375Y53564D01*
X111305Y53231D01*
X111222Y52899D01*
Y52885D01*
X111208Y52857D01*
X111194Y52815D01*
X111180Y52760D01*
X111125Y52607D01*
X111042Y52413D01*
X110958Y52191D01*
X110848Y51969D01*
X110709Y51734D01*
X110570Y51512D01*
X110556Y51484D01*
X110501Y51415D01*
X110417Y51318D01*
X110307Y51193D01*
X110182Y51054D01*
X110029Y50915D01*
X109877Y50763D01*
X109696Y50638D01*
X109669Y50624D01*
X109613Y50582D01*
X109516Y50527D01*
X109377Y50458D01*
X109211Y50374D01*
X109017Y50305D01*
X108795Y50222D01*
X108545Y50153D01*
X108518D01*
X108476Y50139D01*
X108434Y50125D01*
X108296Y50111D01*
X108102Y50083D01*
X107880Y50055D01*
X107616Y50028D01*
X107325Y50014D01*
X107006Y50000D01*
X103553D01*
Y59597D01*
X107242D01*
X107491Y59583D01*
D02*
G37*
G36*
X101569Y58460D02*
X95897D01*
Y55533D01*
X101209D01*
Y54396D01*
X95897D01*
Y51137D01*
X101791D01*
Y50000D01*
X94621D01*
Y59597D01*
X101569D01*
Y58460D01*
D02*
G37*
G36*
X93082D02*
X87660Y51817D01*
X87091Y51137D01*
X93235D01*
Y50000D01*
X85635D01*
Y51179D01*
X90558Y57309D01*
Y57323D01*
X90586Y57336D01*
X90655Y57420D01*
X90752Y57544D01*
X90877Y57697D01*
X91030Y57877D01*
X91196Y58071D01*
X91376Y58266D01*
X91557Y58460D01*
X86189D01*
Y59597D01*
X93082D01*
Y58460D01*
D02*
G37*
G36*
X78146Y59625D02*
X78257Y59611D01*
X78395Y59597D01*
X78548Y59569D01*
X78700Y59542D01*
X79061Y59444D01*
X79422Y59306D01*
X79602Y59222D01*
X79782Y59125D01*
X79949Y59001D01*
X80101Y58862D01*
X80115Y58848D01*
X80143Y58834D01*
X80171Y58779D01*
X80226Y58723D01*
X80295Y58654D01*
X80365Y58557D01*
X80434Y58460D01*
X80517Y58335D01*
X80656Y58071D01*
X80795Y57739D01*
X80850Y57572D01*
X80878Y57378D01*
X80906Y57184D01*
X80919Y56976D01*
Y56948D01*
Y56879D01*
X80906Y56768D01*
X80892Y56615D01*
X80864Y56449D01*
X80808Y56255D01*
X80753Y56047D01*
X80670Y55839D01*
X80656Y55811D01*
X80628Y55742D01*
X80573Y55631D01*
X80490Y55478D01*
X80379Y55312D01*
X80240Y55104D01*
X80073Y54896D01*
X79879Y54660D01*
X79852Y54632D01*
X79782Y54549D01*
X79713Y54479D01*
X79644Y54410D01*
X79560Y54327D01*
X79449Y54216D01*
X79338Y54105D01*
X79200Y53980D01*
X79061Y53842D01*
X78895Y53689D01*
X78714Y53536D01*
X78520Y53356D01*
X78298Y53176D01*
X78076Y52982D01*
X78063Y52968D01*
X78035Y52940D01*
X77979Y52899D01*
X77910Y52843D01*
X77827Y52760D01*
X77730Y52677D01*
X77508Y52496D01*
X77272Y52288D01*
X77050Y52080D01*
X76856Y51900D01*
X76773Y51831D01*
X76704Y51761D01*
X76690Y51747D01*
X76648Y51706D01*
X76592Y51650D01*
X76523Y51567D01*
X76454Y51470D01*
X76371Y51373D01*
X76204Y51137D01*
X80933D01*
Y50000D01*
X74568D01*
Y50014D01*
Y50069D01*
Y50153D01*
X74582Y50264D01*
X74595Y50388D01*
X74623Y50527D01*
X74651Y50666D01*
X74706Y50818D01*
Y50832D01*
X74720Y50846D01*
X74748Y50929D01*
X74804Y51054D01*
X74887Y51220D01*
X74998Y51415D01*
X75136Y51637D01*
X75289Y51858D01*
X75483Y52094D01*
Y52108D01*
X75511Y52122D01*
X75580Y52205D01*
X75705Y52330D01*
X75885Y52510D01*
X76093Y52718D01*
X76357Y52968D01*
X76676Y53245D01*
X77022Y53536D01*
X77036Y53550D01*
X77092Y53592D01*
X77175Y53661D01*
X77272Y53745D01*
X77397Y53855D01*
X77549Y53980D01*
X77702Y54119D01*
X77882Y54271D01*
X78229Y54604D01*
X78576Y54937D01*
X78742Y55104D01*
X78895Y55270D01*
X79033Y55423D01*
X79144Y55575D01*
Y55589D01*
X79172Y55603D01*
X79200Y55644D01*
X79227Y55700D01*
X79325Y55852D01*
X79436Y56033D01*
X79533Y56255D01*
X79630Y56490D01*
X79685Y56754D01*
X79713Y57003D01*
Y57017D01*
Y57031D01*
X79699Y57115D01*
X79685Y57253D01*
X79644Y57406D01*
X79588Y57600D01*
X79491Y57794D01*
X79366Y57988D01*
X79200Y58182D01*
X79172Y58210D01*
X79103Y58266D01*
X79006Y58335D01*
X78853Y58432D01*
X78659Y58515D01*
X78437Y58598D01*
X78173Y58654D01*
X77882Y58668D01*
X77799D01*
X77744Y58654D01*
X77577Y58640D01*
X77383Y58598D01*
X77175Y58543D01*
X76939Y58446D01*
X76717Y58321D01*
X76509Y58155D01*
X76482Y58127D01*
X76426Y58057D01*
X76343Y57947D01*
X76260Y57780D01*
X76163Y57586D01*
X76079Y57336D01*
X76024Y57059D01*
X75996Y56740D01*
X74790Y56865D01*
Y56879D01*
X74804Y56920D01*
Y56990D01*
X74817Y57087D01*
X74845Y57198D01*
X74873Y57323D01*
X74914Y57475D01*
X74956Y57628D01*
X75067Y57961D01*
X75233Y58293D01*
X75331Y58460D01*
X75455Y58626D01*
X75580Y58779D01*
X75719Y58917D01*
X75733Y58931D01*
X75760Y58945D01*
X75802Y58987D01*
X75871Y59028D01*
X75955Y59084D01*
X76052Y59139D01*
X76163Y59209D01*
X76301Y59278D01*
X76454Y59347D01*
X76620Y59417D01*
X76800Y59472D01*
X76995Y59528D01*
X77203Y59569D01*
X77425Y59611D01*
X77660Y59625D01*
X77910Y59639D01*
X78049D01*
X78146Y59625D01*
D02*
G37*
G36*
X29828Y106969D02*
X30011Y106941D01*
X30237Y106899D01*
X30491Y106828D01*
X30745Y106744D01*
X30998Y106631D01*
X31012D01*
X31026Y106617D01*
X31111Y106574D01*
X31238Y106490D01*
X31379Y106391D01*
X31548Y106250D01*
X31717Y106095D01*
X31886Y105912D01*
X32027Y105701D01*
X32041Y105672D01*
X32084Y105602D01*
X32140Y105475D01*
X32211Y105320D01*
X32281Y105137D01*
X32338Y104925D01*
X32380Y104685D01*
X32394Y104446D01*
Y104418D01*
Y104333D01*
X32380Y104220D01*
X32352Y104065D01*
X32309Y103882D01*
X32239Y103685D01*
X32154Y103487D01*
X32041Y103290D01*
X32027Y103262D01*
X31985Y103205D01*
X31900Y103107D01*
X31788Y102994D01*
X31647Y102867D01*
X31478Y102726D01*
X31280Y102599D01*
X31041Y102472D01*
X31055D01*
X31083Y102458D01*
X31125Y102444D01*
X31181Y102430D01*
X31337Y102374D01*
X31534Y102289D01*
X31760Y102176D01*
X31985Y102035D01*
X32197Y101852D01*
X32394Y101641D01*
X32408Y101612D01*
X32464Y101528D01*
X32549Y101387D01*
X32634Y101203D01*
X32718Y100978D01*
X32803Y100710D01*
X32859Y100400D01*
X32873Y100062D01*
Y100048D01*
Y100005D01*
Y99935D01*
X32859Y99850D01*
X32845Y99737D01*
X32817Y99611D01*
X32789Y99470D01*
X32760Y99314D01*
X32648Y98976D01*
X32563Y98793D01*
X32478Y98624D01*
X32366Y98441D01*
X32239Y98257D01*
X32098Y98074D01*
X31929Y97905D01*
X31915Y97891D01*
X31886Y97863D01*
X31830Y97820D01*
X31760Y97764D01*
X31675Y97693D01*
X31562Y97623D01*
X31435Y97538D01*
X31280Y97468D01*
X31125Y97383D01*
X30942Y97299D01*
X30759Y97228D01*
X30547Y97158D01*
X30322Y97101D01*
X30082Y97059D01*
X29842Y97031D01*
X29574Y97017D01*
X29448D01*
X29363Y97031D01*
X29250Y97045D01*
X29123Y97059D01*
X28982Y97087D01*
X28827Y97115D01*
X28489Y97200D01*
X28137Y97341D01*
X27953Y97425D01*
X27784Y97524D01*
X27615Y97651D01*
X27446Y97778D01*
X27432Y97792D01*
X27404Y97820D01*
X27361Y97863D01*
X27319Y97919D01*
X27248Y97989D01*
X27178Y98088D01*
X27093Y98187D01*
X27009Y98314D01*
X26924Y98455D01*
X26840Y98596D01*
X26685Y98934D01*
X26558Y99329D01*
X26515Y99540D01*
X26487Y99766D01*
X27685Y99921D01*
Y99907D01*
X27700Y99878D01*
X27714Y99822D01*
X27728Y99752D01*
X27742Y99667D01*
X27770Y99568D01*
X27841Y99357D01*
X27939Y99103D01*
X28066Y98863D01*
X28207Y98638D01*
X28376Y98441D01*
X28404Y98426D01*
X28461Y98370D01*
X28574Y98300D01*
X28715Y98229D01*
X28884Y98145D01*
X29095Y98074D01*
X29335Y98018D01*
X29589Y98004D01*
X29673D01*
X29730Y98018D01*
X29885Y98032D01*
X30082Y98074D01*
X30308Y98145D01*
X30547Y98243D01*
X30787Y98384D01*
X31012Y98581D01*
X31041Y98610D01*
X31111Y98694D01*
X31196Y98821D01*
X31308Y98990D01*
X31421Y99202D01*
X31506Y99441D01*
X31576Y99723D01*
X31604Y100034D01*
Y100048D01*
Y100076D01*
Y100118D01*
X31590Y100175D01*
X31576Y100330D01*
X31534Y100513D01*
X31478Y100738D01*
X31379Y100964D01*
X31238Y101189D01*
X31055Y101401D01*
X31026Y101429D01*
X30956Y101486D01*
X30843Y101570D01*
X30688Y101669D01*
X30491Y101767D01*
X30251Y101852D01*
X29983Y101908D01*
X29687Y101937D01*
X29560D01*
X29462Y101923D01*
X29335Y101908D01*
X29194Y101880D01*
X29025Y101852D01*
X28841Y101810D01*
X28982Y102867D01*
X29053D01*
X29109Y102853D01*
X29293D01*
X29448Y102881D01*
X29631Y102909D01*
X29842Y102952D01*
X30082Y103022D01*
X30308Y103121D01*
X30547Y103248D01*
X30561D01*
X30575Y103262D01*
X30646Y103318D01*
X30745Y103417D01*
X30857Y103544D01*
X30970Y103727D01*
X31069Y103938D01*
X31139Y104178D01*
X31168Y104319D01*
Y104474D01*
Y104488D01*
Y104502D01*
Y104587D01*
X31139Y104700D01*
X31111Y104855D01*
X31055Y105024D01*
X30984Y105207D01*
X30871Y105390D01*
X30716Y105560D01*
X30702Y105574D01*
X30632Y105630D01*
X30533Y105701D01*
X30406Y105785D01*
X30237Y105856D01*
X30040Y105926D01*
X29814Y105982D01*
X29560Y105997D01*
X29448D01*
X29321Y105968D01*
X29152Y105940D01*
X28968Y105884D01*
X28785Y105813D01*
X28588Y105701D01*
X28404Y105560D01*
X28390Y105545D01*
X28334Y105475D01*
X28249Y105376D01*
X28151Y105235D01*
X28052Y105052D01*
X27953Y104826D01*
X27869Y104559D01*
X27812Y104249D01*
X26614Y104460D01*
Y104474D01*
X26628Y104516D01*
X26642Y104573D01*
X26656Y104657D01*
X26685Y104756D01*
X26727Y104869D01*
X26811Y105137D01*
X26952Y105447D01*
X27122Y105757D01*
X27333Y106053D01*
X27601Y106321D01*
X27615Y106335D01*
X27643Y106349D01*
X27685Y106377D01*
X27742Y106419D01*
X27812Y106476D01*
X27911Y106532D01*
X28010Y106589D01*
X28137Y106659D01*
X28419Y106772D01*
X28743Y106885D01*
X29123Y106955D01*
X29321Y106983D01*
X29673D01*
X29828Y106969D01*
D02*
G37*
G36*
X21130Y106927D02*
X21412Y106913D01*
X21694Y106885D01*
X21976Y106842D01*
X22216Y106800D01*
X22230D01*
X22258Y106786D01*
X22300D01*
X22357Y106758D01*
X22512Y106715D01*
X22709Y106645D01*
X22935Y106546D01*
X23175Y106419D01*
X23414Y106278D01*
X23640Y106095D01*
X23654Y106081D01*
X23668Y106067D01*
X23710Y106025D01*
X23767Y105982D01*
X23907Y105841D01*
X24077Y105644D01*
X24260Y105404D01*
X24457Y105122D01*
X24641Y104798D01*
X24796Y104432D01*
Y104418D01*
X24810Y104389D01*
X24838Y104333D01*
X24852Y104249D01*
X24894Y104150D01*
X24922Y104037D01*
X24951Y103910D01*
X24993Y103755D01*
X25035Y103600D01*
X25064Y103417D01*
X25134Y103022D01*
X25176Y102585D01*
X25190Y102106D01*
Y102092D01*
Y102063D01*
Y101993D01*
Y101923D01*
X25176Y101824D01*
Y101711D01*
X25162Y101443D01*
X25120Y101133D01*
X25078Y100809D01*
X25007Y100471D01*
X24922Y100132D01*
Y100118D01*
X24908Y100090D01*
X24894Y100048D01*
X24880Y99991D01*
X24824Y99836D01*
X24739Y99639D01*
X24655Y99413D01*
X24542Y99188D01*
X24401Y98948D01*
X24260Y98722D01*
X24246Y98694D01*
X24189Y98624D01*
X24105Y98525D01*
X23992Y98398D01*
X23865Y98257D01*
X23710Y98116D01*
X23555Y97961D01*
X23372Y97834D01*
X23344Y97820D01*
X23287Y97778D01*
X23189Y97722D01*
X23048Y97651D01*
X22878Y97566D01*
X22681Y97496D01*
X22455Y97411D01*
X22202Y97341D01*
X22174D01*
X22131Y97327D01*
X22089Y97313D01*
X21948Y97299D01*
X21751Y97270D01*
X21525Y97242D01*
X21257Y97214D01*
X20961Y97200D01*
X20637Y97186D01*
X17127D01*
Y106941D01*
X20877D01*
X21130Y106927D01*
D02*
G37*
G36*
X211990Y104885D02*
X212103Y104871D01*
X212244Y104856D01*
X212399Y104828D01*
X212554Y104800D01*
X212921Y104701D01*
X213287Y104560D01*
X213470Y104476D01*
X213654Y104377D01*
X213823Y104250D01*
X213978Y104109D01*
X213992Y104095D01*
X214020Y104081D01*
X214049Y104025D01*
X214105Y103968D01*
X214175Y103898D01*
X214246Y103799D01*
X214316Y103701D01*
X214401Y103574D01*
X214542Y103306D01*
X214683Y102967D01*
X214739Y102798D01*
X214767Y102601D01*
X214796Y102404D01*
X214810Y102192D01*
Y102164D01*
Y102093D01*
X214796Y101981D01*
X214781Y101826D01*
X214753Y101656D01*
X214697Y101459D01*
X214641Y101248D01*
X214556Y101036D01*
X214542Y101008D01*
X214514Y100938D01*
X214457Y100825D01*
X214373Y100670D01*
X214260Y100500D01*
X214119Y100289D01*
X213950Y100077D01*
X213752Y99838D01*
X213724Y99810D01*
X213654Y99725D01*
X213583Y99655D01*
X213513Y99584D01*
X213428Y99500D01*
X213315Y99387D01*
X213203Y99274D01*
X213062Y99147D01*
X212921Y99006D01*
X212752Y98851D01*
X212568Y98696D01*
X212371Y98513D01*
X212145Y98329D01*
X211920Y98132D01*
X211906Y98118D01*
X211878Y98090D01*
X211821Y98048D01*
X211751Y97991D01*
X211666Y97907D01*
X211567Y97822D01*
X211342Y97639D01*
X211102Y97427D01*
X210877Y97216D01*
X210679Y97033D01*
X210595Y96962D01*
X210524Y96892D01*
X210510Y96877D01*
X210468Y96835D01*
X210411Y96779D01*
X210341Y96694D01*
X210271Y96596D01*
X210186Y96497D01*
X210017Y96257D01*
X214824D01*
Y95101D01*
X208353D01*
Y95115D01*
Y95172D01*
Y95256D01*
X208367Y95369D01*
X208382Y95496D01*
X208410Y95637D01*
X208438Y95778D01*
X208494Y95933D01*
Y95947D01*
X208508Y95961D01*
X208537Y96046D01*
X208593Y96173D01*
X208678Y96342D01*
X208790Y96539D01*
X208931Y96765D01*
X209086Y96990D01*
X209284Y97230D01*
Y97244D01*
X209312Y97258D01*
X209382Y97343D01*
X209509Y97470D01*
X209692Y97653D01*
X209904Y97864D01*
X210172Y98118D01*
X210496Y98400D01*
X210849Y98696D01*
X210863Y98710D01*
X210919Y98752D01*
X211003Y98823D01*
X211102Y98907D01*
X211229Y99020D01*
X211384Y99147D01*
X211539Y99288D01*
X211723Y99443D01*
X212075Y99782D01*
X212427Y100120D01*
X212596Y100289D01*
X212752Y100458D01*
X212892Y100613D01*
X213005Y100768D01*
Y100782D01*
X213034Y100796D01*
X213062Y100839D01*
X213090Y100895D01*
X213189Y101050D01*
X213301Y101234D01*
X213400Y101459D01*
X213499Y101699D01*
X213555Y101966D01*
X213583Y102220D01*
Y102234D01*
Y102248D01*
X213569Y102333D01*
X213555Y102474D01*
X213513Y102629D01*
X213456Y102826D01*
X213358Y103024D01*
X213231Y103221D01*
X213062Y103419D01*
X213034Y103447D01*
X212963Y103503D01*
X212864Y103574D01*
X212709Y103672D01*
X212512Y103757D01*
X212286Y103841D01*
X212019Y103898D01*
X211723Y103912D01*
X211638D01*
X211581Y103898D01*
X211412Y103884D01*
X211215Y103841D01*
X211003Y103785D01*
X210764Y103686D01*
X210538Y103560D01*
X210327Y103390D01*
X210299Y103362D01*
X210242Y103292D01*
X210158Y103179D01*
X210073Y103010D01*
X209974Y102812D01*
X209890Y102559D01*
X209834Y102277D01*
X209805Y101952D01*
X208579Y102079D01*
Y102093D01*
X208593Y102136D01*
Y102206D01*
X208607Y102305D01*
X208635Y102418D01*
X208663Y102544D01*
X208706Y102700D01*
X208748Y102855D01*
X208861Y103193D01*
X209030Y103531D01*
X209129Y103701D01*
X209256Y103870D01*
X209382Y104025D01*
X209523Y104166D01*
X209538Y104180D01*
X209566Y104194D01*
X209608Y104236D01*
X209678Y104278D01*
X209763Y104335D01*
X209862Y104391D01*
X209974Y104462D01*
X210115Y104532D01*
X210271Y104603D01*
X210440Y104673D01*
X210623Y104730D01*
X210820Y104786D01*
X211032Y104828D01*
X211257Y104871D01*
X211497Y104885D01*
X211751Y104899D01*
X211892D01*
X211990Y104885D01*
D02*
G37*
G36*
X203180Y104842D02*
X203462Y104828D01*
X203744Y104800D01*
X204025Y104758D01*
X204265Y104715D01*
X204279D01*
X204307Y104701D01*
X204350D01*
X204406Y104673D01*
X204561Y104631D01*
X204759Y104560D01*
X204984Y104462D01*
X205224Y104335D01*
X205463Y104194D01*
X205689Y104011D01*
X205703Y103996D01*
X205717Y103982D01*
X205760Y103940D01*
X205816Y103898D01*
X205957Y103757D01*
X206126Y103560D01*
X206309Y103320D01*
X206507Y103038D01*
X206690Y102714D01*
X206845Y102347D01*
Y102333D01*
X206859Y102305D01*
X206887Y102248D01*
X206901Y102164D01*
X206944Y102065D01*
X206972Y101952D01*
X207000Y101826D01*
X207042Y101671D01*
X207085Y101515D01*
X207113Y101332D01*
X207183Y100938D01*
X207225Y100500D01*
X207240Y100021D01*
Y100007D01*
Y99979D01*
Y99908D01*
Y99838D01*
X207225Y99739D01*
Y99626D01*
X207211Y99359D01*
X207169Y99049D01*
X207127Y98724D01*
X207056Y98386D01*
X206972Y98048D01*
Y98034D01*
X206958Y98005D01*
X206944Y97963D01*
X206929Y97907D01*
X206873Y97752D01*
X206789Y97554D01*
X206704Y97329D01*
X206591Y97103D01*
X206450Y96863D01*
X206309Y96638D01*
X206295Y96610D01*
X206239Y96539D01*
X206154Y96440D01*
X206041Y96314D01*
X205914Y96173D01*
X205760Y96032D01*
X205604Y95877D01*
X205421Y95750D01*
X205393Y95736D01*
X205336Y95693D01*
X205238Y95637D01*
X205097Y95567D01*
X204928Y95482D01*
X204730Y95411D01*
X204505Y95327D01*
X204251Y95256D01*
X204223D01*
X204181Y95242D01*
X204138Y95228D01*
X203997Y95214D01*
X203800Y95186D01*
X203574Y95158D01*
X203307Y95129D01*
X203011Y95115D01*
X202686Y95101D01*
X199176D01*
Y104856D01*
X202926D01*
X203180Y104842D01*
D02*
G37*
G36*
X212392Y338634D02*
Y338627D01*
Y338597D01*
Y338560D01*
Y338508D01*
X212384Y338442D01*
Y338368D01*
X212377Y338279D01*
X212370Y338191D01*
X212347Y337991D01*
X212318Y337784D01*
X212274Y337585D01*
X212244Y337489D01*
X212214Y337400D01*
Y337392D01*
X212207Y337378D01*
X212192Y337355D01*
X212177Y337326D01*
X212133Y337245D01*
X212066Y337141D01*
X211978Y337023D01*
X211874Y336905D01*
X211741Y336779D01*
X211579Y336668D01*
X211571D01*
X211556Y336653D01*
X211534Y336646D01*
X211497Y336624D01*
X211453Y336601D01*
X211394Y336579D01*
X211335Y336557D01*
X211261Y336528D01*
X211180Y336498D01*
X211091Y336476D01*
X210995Y336454D01*
X210884Y336432D01*
X210773Y336417D01*
X210655Y336402D01*
X210389Y336387D01*
X210322D01*
X210270Y336395D01*
X210211D01*
X210137Y336402D01*
X210056Y336409D01*
X209975Y336417D01*
X209790Y336446D01*
X209590Y336491D01*
X209398Y336550D01*
X209213Y336631D01*
X209206D01*
X209191Y336646D01*
X209169Y336661D01*
X209139Y336675D01*
X209058Y336735D01*
X208962Y336816D01*
X208851Y336919D01*
X208748Y337038D01*
X208644Y337185D01*
X208563Y337348D01*
Y337355D01*
X208556Y337370D01*
X208548Y337400D01*
X208533Y337437D01*
X208519Y337481D01*
X208504Y337540D01*
X208482Y337607D01*
X208467Y337688D01*
X208452Y337777D01*
X208430Y337873D01*
X208415Y337976D01*
X208400Y338087D01*
X208386Y338213D01*
X208378Y338346D01*
X208371Y338486D01*
Y338634D01*
Y341591D01*
X209051D01*
Y338634D01*
Y338627D01*
Y338605D01*
Y338568D01*
Y338523D01*
X209058Y338471D01*
Y338405D01*
X209066Y338265D01*
X209080Y338102D01*
X209103Y337939D01*
X209132Y337784D01*
X209147Y337718D01*
X209169Y337651D01*
X209177Y337636D01*
X209191Y337599D01*
X209228Y337548D01*
X209273Y337474D01*
X209324Y337400D01*
X209398Y337318D01*
X209487Y337237D01*
X209590Y337171D01*
X209605Y337163D01*
X209642Y337141D01*
X209709Y337119D01*
X209797Y337089D01*
X209901Y337052D01*
X210034Y337030D01*
X210174Y337008D01*
X210330Y337001D01*
X210403D01*
X210448Y337008D01*
X210514D01*
X210581Y337015D01*
X210744Y337045D01*
X210921Y337082D01*
X211091Y337141D01*
X211254Y337222D01*
X211327Y337274D01*
X211394Y337333D01*
X211401Y337341D01*
X211409Y337348D01*
X211423Y337370D01*
X211446Y337400D01*
X211468Y337444D01*
X211497Y337489D01*
X211527Y337555D01*
X211556Y337621D01*
X211586Y337703D01*
X211608Y337799D01*
X211638Y337910D01*
X211660Y338028D01*
X211682Y338161D01*
X211697Y338302D01*
X211712Y338464D01*
Y338634D01*
Y341591D01*
X212392D01*
Y338634D01*
D02*
G37*
G36*
X215629Y336476D02*
X215001D01*
Y340475D01*
X214993Y340467D01*
X214957Y340438D01*
X214912Y340393D01*
X214838Y340342D01*
X214757Y340275D01*
X214653Y340201D01*
X214535Y340120D01*
X214402Y340038D01*
X214395D01*
X214387Y340031D01*
X214343Y340002D01*
X214269Y339965D01*
X214181Y339920D01*
X214077Y339869D01*
X213966Y339817D01*
X213855Y339765D01*
X213744Y339721D01*
Y340327D01*
X213752D01*
X213767Y340342D01*
X213796Y340349D01*
X213833Y340371D01*
X213877Y340393D01*
X213929Y340423D01*
X214055Y340497D01*
X214203Y340578D01*
X214350Y340682D01*
X214506Y340800D01*
X214661Y340925D01*
X214668Y340933D01*
X214676Y340940D01*
X214698Y340962D01*
X214727Y340985D01*
X214794Y341059D01*
X214883Y341147D01*
X214971Y341251D01*
X215067Y341369D01*
X215149Y341487D01*
X215223Y341613D01*
X215629D01*
Y336476D01*
D02*
G37*
G36*
X76962Y406278D02*
X71323D01*
X71309D01*
X71267D01*
X71196D01*
X71112D01*
X71013Y406264D01*
X70886D01*
X70619Y406250D01*
X70308Y406222D01*
X69998Y406179D01*
X69702Y406123D01*
X69575Y406095D01*
X69448Y406053D01*
X69420Y406038D01*
X69350Y406010D01*
X69251Y405940D01*
X69110Y405855D01*
X68969Y405756D01*
X68814Y405616D01*
X68659Y405446D01*
X68532Y405249D01*
X68518Y405221D01*
X68476Y405150D01*
X68433Y405023D01*
X68377Y404854D01*
X68307Y404657D01*
X68264Y404403D01*
X68222Y404135D01*
X68208Y403839D01*
Y403698D01*
X68222Y403614D01*
Y403487D01*
X68236Y403360D01*
X68292Y403050D01*
X68363Y402711D01*
X68476Y402387D01*
X68631Y402077D01*
X68730Y401936D01*
X68842Y401809D01*
X68856Y401795D01*
X68871Y401781D01*
X68913Y401753D01*
X68969Y401711D01*
X69054Y401668D01*
X69138Y401612D01*
X69265Y401555D01*
X69392Y401499D01*
X69547Y401443D01*
X69730Y401400D01*
X69942Y401344D01*
X70167Y401302D01*
X70421Y401259D01*
X70689Y401231D01*
X70999Y401203D01*
X71323D01*
X76962D01*
Y399906D01*
X71323D01*
X71309D01*
X71253D01*
X71182D01*
X71084D01*
X70957Y399920D01*
X70816D01*
X70647Y399934D01*
X70477Y399949D01*
X70097Y399991D01*
X69702Y400047D01*
X69322Y400132D01*
X69138Y400188D01*
X68969Y400244D01*
X68955D01*
X68927Y400259D01*
X68885Y400287D01*
X68828Y400315D01*
X68673Y400400D01*
X68476Y400527D01*
X68250Y400696D01*
X68025Y400893D01*
X67785Y401147D01*
X67574Y401457D01*
Y401471D01*
X67545Y401499D01*
X67531Y401541D01*
X67489Y401612D01*
X67447Y401697D01*
X67404Y401809D01*
X67362Y401922D01*
X67306Y402063D01*
X67249Y402218D01*
X67207Y402387D01*
X67165Y402570D01*
X67122Y402782D01*
X67094Y402993D01*
X67066Y403219D01*
X67038Y403727D01*
Y403853D01*
X67052Y403952D01*
Y404065D01*
X67066Y404206D01*
X67080Y404361D01*
X67094Y404516D01*
X67151Y404868D01*
X67235Y405249D01*
X67348Y405616D01*
X67503Y405968D01*
Y405982D01*
X67531Y406010D01*
X67559Y406053D01*
X67588Y406109D01*
X67700Y406264D01*
X67856Y406447D01*
X68053Y406659D01*
X68278Y406856D01*
X68560Y407053D01*
X68871Y407208D01*
X68885D01*
X68913Y407223D01*
X68969Y407237D01*
X69040Y407265D01*
X69124Y407293D01*
X69237Y407321D01*
X69364Y407364D01*
X69519Y407392D01*
X69688Y407420D01*
X69871Y407462D01*
X70069Y407490D01*
X70280Y407519D01*
X70520Y407547D01*
X70774Y407561D01*
X71041Y407575D01*
X71323D01*
X76962D01*
Y406278D01*
D02*
G37*
G36*
Y394183D02*
Y393210D01*
X70647D01*
Y391885D01*
X69547D01*
Y393210D01*
X67207D01*
Y394408D01*
X69547D01*
Y398652D01*
X70647D01*
X76962Y394183D01*
D02*
G37*
G36*
X7150Y383852D02*
X7262Y383838D01*
X7389Y383810D01*
X7530Y383782D01*
X7685Y383753D01*
X8024Y383641D01*
X8207Y383556D01*
X8376Y383471D01*
X8559Y383359D01*
X8743Y383232D01*
X8926Y383091D01*
X9095Y382922D01*
X9109Y382908D01*
X9137Y382879D01*
X9180Y382823D01*
X9236Y382752D01*
X9307Y382668D01*
X9377Y382555D01*
X9462Y382428D01*
X9532Y382273D01*
X9617Y382118D01*
X9701Y381935D01*
X9772Y381752D01*
X9842Y381540D01*
X9899Y381315D01*
X9941Y381075D01*
X9969Y380835D01*
X9983Y380568D01*
Y380441D01*
X9969Y380356D01*
X9955Y380243D01*
X9941Y380116D01*
X9913Y379975D01*
X9885Y379820D01*
X9800Y379482D01*
X9659Y379130D01*
X9574Y378946D01*
X9476Y378777D01*
X9349Y378608D01*
X9222Y378439D01*
X9208Y378425D01*
X9180Y378396D01*
X9137Y378354D01*
X9081Y378312D01*
X9010Y378242D01*
X8912Y378171D01*
X8813Y378086D01*
X8686Y378002D01*
X8545Y377917D01*
X8404Y377833D01*
X8066Y377678D01*
X7671Y377551D01*
X7460Y377508D01*
X7234Y377480D01*
X7079Y378679D01*
X7093D01*
X7122Y378693D01*
X7178Y378707D01*
X7248Y378721D01*
X7333Y378735D01*
X7432Y378763D01*
X7643Y378834D01*
X7897Y378932D01*
X8137Y379059D01*
X8362Y379200D01*
X8559Y379369D01*
X8573Y379397D01*
X8630Y379454D01*
X8700Y379567D01*
X8771Y379707D01*
X8856Y379877D01*
X8926Y380088D01*
X8982Y380328D01*
X8996Y380582D01*
Y380666D01*
X8982Y380723D01*
X8968Y380878D01*
X8926Y381075D01*
X8856Y381301D01*
X8757Y381540D01*
X8616Y381780D01*
X8418Y382005D01*
X8390Y382034D01*
X8306Y382104D01*
X8179Y382189D01*
X8010Y382301D01*
X7798Y382414D01*
X7559Y382499D01*
X7277Y382569D01*
X6967Y382597D01*
X6952D01*
X6924D01*
X6882D01*
X6826Y382583D01*
X6670Y382569D01*
X6487Y382527D01*
X6262Y382471D01*
X6036Y382372D01*
X5810Y382231D01*
X5599Y382048D01*
X5571Y382020D01*
X5515Y381949D01*
X5430Y381836D01*
X5331Y381681D01*
X5233Y381484D01*
X5148Y381244D01*
X5092Y380976D01*
X5063Y380680D01*
Y380553D01*
X5077Y380455D01*
X5092Y380328D01*
X5120Y380187D01*
X5148Y380018D01*
X5190Y379834D01*
X4133Y379975D01*
Y380046D01*
X4147Y380102D01*
Y380285D01*
X4119Y380441D01*
X4091Y380624D01*
X4048Y380835D01*
X3978Y381075D01*
X3879Y381301D01*
X3752Y381540D01*
Y381554D01*
X3738Y381568D01*
X3682Y381639D01*
X3583Y381738D01*
X3456Y381850D01*
X3273Y381963D01*
X3062Y382062D01*
X2822Y382132D01*
X2681Y382160D01*
X2526D01*
X2512D01*
X2498D01*
X2413D01*
X2300Y382132D01*
X2145Y382104D01*
X1976Y382048D01*
X1793Y381977D01*
X1610Y381864D01*
X1441Y381709D01*
X1426Y381695D01*
X1370Y381625D01*
X1300Y381526D01*
X1215Y381399D01*
X1144Y381230D01*
X1074Y381033D01*
X1018Y380807D01*
X1003Y380553D01*
Y380441D01*
X1032Y380314D01*
X1060Y380145D01*
X1116Y379961D01*
X1187Y379778D01*
X1300Y379581D01*
X1441Y379397D01*
X1455Y379383D01*
X1525Y379327D01*
X1624Y379242D01*
X1765Y379144D01*
X1948Y379045D01*
X2174Y378946D01*
X2441Y378862D01*
X2752Y378805D01*
X2540Y377607D01*
X2526D01*
X2484Y377621D01*
X2427Y377635D01*
X2343Y377649D01*
X2244Y377678D01*
X2131Y377720D01*
X1863Y377804D01*
X1553Y377945D01*
X1243Y378115D01*
X947Y378326D01*
X679Y378594D01*
X665Y378608D01*
X651Y378636D01*
X623Y378679D01*
X580Y378735D01*
X524Y378805D01*
X468Y378904D01*
X411Y379003D01*
X341Y379130D01*
X228Y379412D01*
X115Y379736D01*
X45Y380116D01*
X17Y380314D01*
Y380666D01*
X31Y380821D01*
X59Y381004D01*
X101Y381230D01*
X172Y381484D01*
X256Y381738D01*
X369Y381991D01*
Y382005D01*
X383Y382020D01*
X426Y382104D01*
X510Y382231D01*
X609Y382372D01*
X750Y382541D01*
X905Y382710D01*
X1088Y382879D01*
X1300Y383020D01*
X1328Y383034D01*
X1398Y383077D01*
X1525Y383133D01*
X1680Y383204D01*
X1863Y383274D01*
X2075Y383330D01*
X2315Y383373D01*
X2554Y383387D01*
X2582D01*
X2667D01*
X2780Y383373D01*
X2935Y383345D01*
X3118Y383302D01*
X3315Y383232D01*
X3513Y383147D01*
X3710Y383034D01*
X3738Y383020D01*
X3795Y382978D01*
X3893Y382893D01*
X4006Y382781D01*
X4133Y382640D01*
X4274Y382471D01*
X4401Y382273D01*
X4528Y382034D01*
Y382048D01*
X4542Y382076D01*
X4556Y382118D01*
X4570Y382174D01*
X4626Y382330D01*
X4711Y382527D01*
X4824Y382752D01*
X4965Y382978D01*
X5148Y383190D01*
X5359Y383387D01*
X5388Y383401D01*
X5472Y383457D01*
X5613Y383542D01*
X5796Y383627D01*
X6022Y383711D01*
X6290Y383796D01*
X6600Y383852D01*
X6938Y383866D01*
X6952D01*
X6995D01*
X7065D01*
X7150Y383852D01*
D02*
G37*
G36*
X6064Y375789D02*
X6205D01*
X6374Y375774D01*
X6544Y375760D01*
X6924Y375718D01*
X7319Y375662D01*
X7699Y375577D01*
X7883Y375521D01*
X8052Y375464D01*
X8066D01*
X8094Y375450D01*
X8137Y375422D01*
X8193Y375394D01*
X8348Y375309D01*
X8545Y375182D01*
X8771Y375013D01*
X8996Y374816D01*
X9236Y374562D01*
X9448Y374252D01*
Y374238D01*
X9476Y374210D01*
X9490Y374167D01*
X9532Y374097D01*
X9574Y374012D01*
X9617Y373900D01*
X9659Y373787D01*
X9715Y373646D01*
X9772Y373491D01*
X9814Y373322D01*
X9856Y373138D01*
X9899Y372927D01*
X9927Y372715D01*
X9955Y372490D01*
X9983Y371982D01*
Y371856D01*
X9969Y371757D01*
Y371644D01*
X9955Y371503D01*
X9941Y371348D01*
X9927Y371193D01*
X9870Y370840D01*
X9786Y370460D01*
X9673Y370093D01*
X9518Y369741D01*
Y369727D01*
X9490Y369699D01*
X9462Y369656D01*
X9434Y369600D01*
X9321Y369445D01*
X9166Y369262D01*
X8968Y369050D01*
X8743Y368853D01*
X8461Y368656D01*
X8151Y368500D01*
X8137D01*
X8108Y368486D01*
X8052Y368472D01*
X7982Y368444D01*
X7897Y368416D01*
X7784Y368388D01*
X7657Y368345D01*
X7502Y368317D01*
X7333Y368289D01*
X7150Y368247D01*
X6952Y368218D01*
X6741Y368190D01*
X6501Y368162D01*
X6248Y368148D01*
X5980Y368134D01*
X5698D01*
X59D01*
Y369431D01*
X5698D01*
X5712D01*
X5754D01*
X5825D01*
X5909D01*
X6008Y369445D01*
X6135D01*
X6403Y369459D01*
X6713Y369487D01*
X7023Y369529D01*
X7319Y369586D01*
X7446Y369614D01*
X7573Y369656D01*
X7601Y369670D01*
X7671Y369699D01*
X7770Y369769D01*
X7911Y369854D01*
X8052Y369952D01*
X8207Y370093D01*
X8362Y370263D01*
X8489Y370460D01*
X8503Y370488D01*
X8545Y370559D01*
X8588Y370686D01*
X8644Y370855D01*
X8715Y371052D01*
X8757Y371306D01*
X8799Y371574D01*
X8813Y371870D01*
Y372011D01*
X8799Y372095D01*
Y372222D01*
X8785Y372349D01*
X8729Y372659D01*
X8658Y372997D01*
X8545Y373322D01*
X8390Y373632D01*
X8292Y373773D01*
X8179Y373900D01*
X8165Y373914D01*
X8151Y373928D01*
X8108Y373956D01*
X8052Y373998D01*
X7967Y374041D01*
X7883Y374097D01*
X7756Y374153D01*
X7629Y374210D01*
X7474Y374266D01*
X7291Y374308D01*
X7079Y374365D01*
X6854Y374407D01*
X6600Y374449D01*
X6332Y374478D01*
X6022Y374506D01*
X5698D01*
X59D01*
Y375803D01*
X5698D01*
X5712D01*
X5768D01*
X5839D01*
X5937D01*
X6064Y375789D01*
D02*
G37*
G36*
X-13751Y328651D02*
X-13653Y328637D01*
X-13526Y328623D01*
X-13385Y328595D01*
X-13230Y328553D01*
X-12906Y328454D01*
X-12723Y328383D01*
X-12553Y328285D01*
X-12370Y328186D01*
X-12201Y328073D01*
X-12032Y327932D01*
X-11862Y327777D01*
X-11848Y327763D01*
X-11820Y327735D01*
X-11778Y327693D01*
X-11736Y327622D01*
X-11665Y327523D01*
X-11595Y327425D01*
X-11524Y327298D01*
X-11440Y327157D01*
X-11355Y327002D01*
X-11285Y326819D01*
X-11214Y326621D01*
X-11144Y326424D01*
X-11101Y326198D01*
X-11059Y325959D01*
X-11031Y325719D01*
X-11017Y325451D01*
Y325310D01*
X-11031Y325211D01*
X-11045Y325085D01*
X-11059Y324944D01*
X-11087Y324789D01*
X-11129Y324619D01*
X-11228Y324239D01*
X-11299Y324041D01*
X-11369Y323858D01*
X-11468Y323661D01*
X-11581Y323464D01*
X-11708Y323280D01*
X-11862Y323111D01*
X-11877Y323097D01*
X-11905Y323069D01*
X-11947Y323027D01*
X-12018Y322970D01*
X-12102Y322914D01*
X-12201Y322829D01*
X-12314Y322759D01*
X-12455Y322674D01*
X-12596Y322589D01*
X-12765Y322519D01*
X-13117Y322378D01*
X-13329Y322322D01*
X-13540Y322279D01*
X-13766Y322251D01*
X-13991Y322237D01*
X-14005D01*
X-14033D01*
X-14090D01*
X-14146Y322251D01*
X-14231D01*
X-14330Y322265D01*
X-14555Y322293D01*
X-14809Y322350D01*
X-15063Y322434D01*
X-15330Y322561D01*
X-15584Y322716D01*
X-15598D01*
X-15612Y322744D01*
X-15683Y322801D01*
X-15796Y322914D01*
X-15937Y323069D01*
X-16078Y323266D01*
X-16233Y323506D01*
X-16359Y323774D01*
X-16458Y324098D01*
Y324084D01*
X-16472Y324070D01*
X-16486Y324027D01*
X-16515Y323971D01*
X-16571Y323844D01*
X-16655Y323675D01*
X-16768Y323492D01*
X-16909Y323308D01*
X-17064Y323139D01*
X-17234Y322984D01*
X-17262Y322970D01*
X-17318Y322928D01*
X-17431Y322871D01*
X-17572Y322815D01*
X-17755Y322744D01*
X-17967Y322688D01*
X-18206Y322646D01*
X-18460Y322632D01*
X-18474D01*
X-18502D01*
X-18559D01*
X-18643Y322646D01*
X-18728Y322660D01*
X-18841Y322674D01*
X-19080Y322730D01*
X-19362Y322815D01*
X-19658Y322956D01*
X-19813Y323041D01*
X-19968Y323139D01*
X-20109Y323266D01*
X-20250Y323393D01*
X-20264Y323407D01*
X-20278Y323435D01*
X-20321Y323478D01*
X-20363Y323534D01*
X-20419Y323605D01*
X-20476Y323703D01*
X-20546Y323816D01*
X-20617Y323929D01*
X-20687Y324070D01*
X-20758Y324225D01*
X-20814Y324394D01*
X-20870Y324577D01*
X-20955Y324972D01*
X-20969Y325197D01*
X-20983Y325423D01*
Y325550D01*
X-20969Y325634D01*
X-20955Y325747D01*
X-20941Y325874D01*
X-20927Y326015D01*
X-20885Y326156D01*
X-20800Y326494D01*
X-20673Y326833D01*
X-20589Y327002D01*
X-20490Y327171D01*
X-20363Y327326D01*
X-20236Y327481D01*
X-20222Y327495D01*
X-20208Y327509D01*
X-20166Y327552D01*
X-20109Y327608D01*
X-20025Y327664D01*
X-19940Y327735D01*
X-19729Y327876D01*
X-19461Y328017D01*
X-19151Y328144D01*
X-18798Y328242D01*
X-18615Y328256D01*
X-18418Y328271D01*
X-18404D01*
X-18389D01*
X-18305D01*
X-18178Y328256D01*
X-18023Y328228D01*
X-17826Y328186D01*
X-17628Y328116D01*
X-17431Y328031D01*
X-17234Y327904D01*
X-17205Y327890D01*
X-17149Y327834D01*
X-17064Y327749D01*
X-16952Y327636D01*
X-16825Y327481D01*
X-16698Y327298D01*
X-16571Y327086D01*
X-16458Y326833D01*
Y326847D01*
X-16444Y326875D01*
X-16430Y326917D01*
X-16402Y326974D01*
X-16331Y327143D01*
X-16233Y327340D01*
X-16092Y327552D01*
X-15937Y327777D01*
X-15739Y327989D01*
X-15514Y328186D01*
X-15500D01*
X-15486Y328200D01*
X-15401Y328256D01*
X-15260Y328341D01*
X-15077Y328426D01*
X-14851Y328510D01*
X-14583Y328595D01*
X-14287Y328651D01*
X-13963Y328665D01*
X-13949D01*
X-13907D01*
X-13836D01*
X-13751Y328651D01*
D02*
G37*
G36*
X-11186Y317980D02*
X-18812D01*
X-18798Y317966D01*
X-18742Y317895D01*
X-18657Y317811D01*
X-18559Y317670D01*
X-18432Y317515D01*
X-18291Y317317D01*
X-18136Y317092D01*
X-17981Y316838D01*
Y316824D01*
X-17967Y316810D01*
X-17910Y316725D01*
X-17840Y316584D01*
X-17755Y316415D01*
X-17656Y316218D01*
X-17558Y316006D01*
X-17459Y315795D01*
X-17375Y315583D01*
X-18530D01*
Y315597D01*
X-18559Y315626D01*
X-18573Y315682D01*
X-18615Y315752D01*
X-18657Y315837D01*
X-18714Y315936D01*
X-18855Y316175D01*
X-19010Y316457D01*
X-19207Y316739D01*
X-19433Y317035D01*
X-19672Y317331D01*
X-19686Y317345D01*
X-19700Y317360D01*
X-19743Y317402D01*
X-19785Y317458D01*
X-19926Y317585D01*
X-20095Y317754D01*
X-20292Y317923D01*
X-20518Y318107D01*
X-20744Y318262D01*
X-20983Y318403D01*
Y319178D01*
X-11186D01*
Y317980D01*
D02*
G37*
G36*
Y312299D02*
X-13216Y311016D01*
X-13230D01*
X-13258Y310988D01*
X-13300Y310959D01*
X-13357Y310917D01*
X-13512Y310819D01*
X-13709Y310692D01*
X-13921Y310536D01*
X-14146Y310382D01*
X-14358Y310226D01*
X-14555Y310085D01*
X-14569Y310071D01*
X-14626Y310029D01*
X-14710Y309959D01*
X-14809Y309860D01*
X-15020Y309648D01*
X-15119Y309536D01*
X-15203Y309423D01*
X-15218Y309409D01*
X-15232Y309381D01*
X-15260Y309324D01*
X-15302Y309240D01*
X-15345Y309155D01*
X-15387Y309056D01*
X-15457Y308831D01*
Y308817D01*
X-15471Y308789D01*
Y308732D01*
X-15486Y308662D01*
X-15500Y308563D01*
Y308450D01*
X-15514Y308295D01*
Y306632D01*
X-11186D01*
Y305335D01*
X-20941D01*
Y309860D01*
X-20927Y309973D01*
Y310100D01*
X-20913Y310396D01*
X-20870Y310706D01*
X-20828Y311044D01*
X-20758Y311354D01*
X-20715Y311509D01*
X-20673Y311636D01*
Y311650D01*
X-20659Y311664D01*
X-20617Y311749D01*
X-20560Y311876D01*
X-20462Y312031D01*
X-20335Y312200D01*
X-20166Y312383D01*
X-19968Y312552D01*
X-19743Y312722D01*
X-19729D01*
X-19715Y312736D01*
X-19630Y312792D01*
X-19489Y312848D01*
X-19306Y312933D01*
X-19094Y313004D01*
X-18841Y313074D01*
X-18573Y313116D01*
X-18277Y313130D01*
X-18263D01*
X-18234D01*
X-18178D01*
X-18108Y313116D01*
X-18009D01*
X-17910Y313102D01*
X-17671Y313046D01*
X-17389Y312961D01*
X-17092Y312848D01*
X-16796Y312679D01*
X-16655Y312567D01*
X-16515Y312454D01*
X-16500Y312440D01*
X-16486Y312425D01*
X-16444Y312383D01*
X-16402Y312327D01*
X-16345Y312256D01*
X-16289Y312172D01*
X-16219Y312059D01*
X-16134Y311946D01*
X-16063Y311805D01*
X-15993Y311650D01*
X-15908Y311481D01*
X-15838Y311298D01*
X-15782Y311086D01*
X-15711Y310875D01*
X-15669Y310635D01*
X-15626Y310382D01*
X-15612Y310410D01*
X-15584Y310466D01*
X-15528Y310551D01*
X-15471Y310663D01*
X-15316Y310917D01*
X-15218Y311044D01*
X-15133Y311157D01*
X-15105Y311185D01*
X-15034Y311255D01*
X-14922Y311368D01*
X-14781Y311509D01*
X-14583Y311664D01*
X-14372Y311848D01*
X-14118Y312031D01*
X-13836Y312228D01*
X-11186Y313906D01*
Y312299D01*
D02*
G37*
G36*
X-17771Y356644D02*
X-17743Y356616D01*
X-17686Y356560D01*
X-17602Y356503D01*
X-17503Y356419D01*
X-17390Y356306D01*
X-17249Y356193D01*
X-17080Y356066D01*
X-16911Y355939D01*
X-16714Y355784D01*
X-16488Y355629D01*
X-16263Y355474D01*
X-16009Y355305D01*
X-15741Y355136D01*
X-15445Y354967D01*
X-15149Y354797D01*
X-15135Y354783D01*
X-15079Y354755D01*
X-14994Y354713D01*
X-14867Y354642D01*
X-14712Y354572D01*
X-14543Y354487D01*
X-14345Y354389D01*
X-14120Y354290D01*
X-13866Y354177D01*
X-13612Y354050D01*
X-13330Y353937D01*
X-13034Y353825D01*
X-12428Y353599D01*
X-11780Y353388D01*
X-11766D01*
X-11723Y353374D01*
X-11653Y353359D01*
X-11568Y353331D01*
X-11456Y353303D01*
X-11315Y353275D01*
X-11159Y353233D01*
X-10990Y353204D01*
X-10793Y353162D01*
X-10582Y353120D01*
X-10130Y353049D01*
X-9637Y352979D01*
X-9101Y352937D01*
Y351710D01*
X-9115D01*
X-9158D01*
X-9214D01*
X-9299Y351724D01*
X-9412D01*
X-9552Y351738D01*
X-9707Y351753D01*
X-9877Y351767D01*
X-10074Y351795D01*
X-10271Y351823D01*
X-10511Y351865D01*
X-10751Y351908D01*
X-11004Y351950D01*
X-11286Y352006D01*
X-11864Y352147D01*
X-11878D01*
X-11935Y352161D01*
X-12019Y352189D01*
X-12146Y352232D01*
X-12287Y352274D01*
X-12456Y352331D01*
X-12654Y352387D01*
X-12865Y352471D01*
X-13105Y352556D01*
X-13345Y352641D01*
X-13880Y352852D01*
X-14444Y353106D01*
X-15008Y353388D01*
X-15022Y353402D01*
X-15079Y353430D01*
X-15149Y353472D01*
X-15262Y353529D01*
X-15389Y353599D01*
X-15544Y353698D01*
X-15713Y353797D01*
X-15896Y353909D01*
X-16305Y354177D01*
X-16728Y354459D01*
X-17165Y354783D01*
X-17574Y355122D01*
Y350343D01*
X-18730D01*
Y356658D01*
X-17785D01*
X-17771Y356644D01*
D02*
G37*
G36*
X-9101Y345987D02*
X-16728D01*
X-16714Y345973D01*
X-16657Y345902D01*
X-16573Y345818D01*
X-16474Y345677D01*
X-16347Y345522D01*
X-16206Y345324D01*
X-16051Y345099D01*
X-15896Y344845D01*
Y344831D01*
X-15882Y344817D01*
X-15826Y344732D01*
X-15755Y344591D01*
X-15670Y344422D01*
X-15572Y344225D01*
X-15473Y344013D01*
X-15374Y343802D01*
X-15290Y343590D01*
X-16446D01*
Y343604D01*
X-16474Y343633D01*
X-16488Y343689D01*
X-16530Y343759D01*
X-16573Y343844D01*
X-16629Y343943D01*
X-16770Y344182D01*
X-16925Y344464D01*
X-17122Y344746D01*
X-17348Y345042D01*
X-17588Y345338D01*
X-17602Y345352D01*
X-17616Y345367D01*
X-17658Y345409D01*
X-17701Y345465D01*
X-17842Y345592D01*
X-18011Y345761D01*
X-18208Y345930D01*
X-18434Y346114D01*
X-18659Y346269D01*
X-18899Y346410D01*
Y347185D01*
X-9101D01*
Y345987D01*
D02*
G37*
G36*
Y340306D02*
X-11131Y339023D01*
X-11145D01*
X-11174Y338995D01*
X-11216Y338966D01*
X-11272Y338924D01*
X-11427Y338825D01*
X-11625Y338699D01*
X-11836Y338544D01*
X-12062Y338388D01*
X-12273Y338233D01*
X-12471Y338092D01*
X-12485Y338078D01*
X-12541Y338036D01*
X-12626Y337966D01*
X-12724Y337867D01*
X-12936Y337655D01*
X-13034Y337543D01*
X-13119Y337430D01*
X-13133Y337416D01*
X-13147Y337388D01*
X-13175Y337331D01*
X-13218Y337247D01*
X-13260Y337162D01*
X-13302Y337063D01*
X-13373Y336838D01*
Y336824D01*
X-13387Y336796D01*
Y336739D01*
X-13401Y336669D01*
X-13415Y336570D01*
Y336457D01*
X-13429Y336302D01*
Y334639D01*
X-9101D01*
Y333342D01*
X-18857D01*
Y337867D01*
X-18842Y337980D01*
Y338107D01*
X-18828Y338403D01*
X-18786Y338713D01*
X-18744Y339051D01*
X-18673Y339361D01*
X-18631Y339516D01*
X-18589Y339643D01*
Y339657D01*
X-18575Y339671D01*
X-18532Y339756D01*
X-18476Y339883D01*
X-18377Y340038D01*
X-18250Y340207D01*
X-18081Y340390D01*
X-17884Y340560D01*
X-17658Y340729D01*
X-17644D01*
X-17630Y340743D01*
X-17545Y340799D01*
X-17405Y340855D01*
X-17221Y340940D01*
X-17010Y341011D01*
X-16756Y341081D01*
X-16488Y341123D01*
X-16192Y341137D01*
X-16178D01*
X-16150D01*
X-16093D01*
X-16023Y341123D01*
X-15924D01*
X-15826Y341109D01*
X-15586Y341053D01*
X-15304Y340968D01*
X-15008Y340855D01*
X-14712Y340686D01*
X-14571Y340574D01*
X-14430Y340461D01*
X-14416Y340447D01*
X-14402Y340433D01*
X-14360Y340390D01*
X-14317Y340334D01*
X-14261Y340263D01*
X-14204Y340179D01*
X-14134Y340066D01*
X-14049Y339953D01*
X-13979Y339812D01*
X-13908Y339657D01*
X-13824Y339488D01*
X-13753Y339305D01*
X-13697Y339093D01*
X-13627Y338882D01*
X-13584Y338642D01*
X-13542Y338388D01*
X-13528Y338417D01*
X-13500Y338473D01*
X-13443Y338558D01*
X-13387Y338671D01*
X-13232Y338924D01*
X-13133Y339051D01*
X-13048Y339164D01*
X-13020Y339192D01*
X-12950Y339263D01*
X-12837Y339375D01*
X-12696Y339516D01*
X-12499Y339671D01*
X-12287Y339855D01*
X-12033Y340038D01*
X-11752Y340235D01*
X-9101Y341913D01*
Y340306D01*
D02*
G37*
G36*
X206856Y406552D02*
X206842Y406340D01*
X206828Y406101D01*
X206814Y405847D01*
X206786Y405607D01*
X206758Y405396D01*
Y405367D01*
X206730Y405269D01*
X206701Y405142D01*
X206659Y404973D01*
X206589Y404789D01*
X206504Y404592D01*
X206405Y404381D01*
X206293Y404197D01*
X206278Y404169D01*
X206236Y404113D01*
X206152Y404028D01*
X206053Y403915D01*
X205926Y403788D01*
X205757Y403662D01*
X205574Y403521D01*
X205362Y403408D01*
X205334Y403394D01*
X205264Y403366D01*
X205137Y403309D01*
X204967Y403253D01*
X204770Y403211D01*
X204545Y403154D01*
X204291Y403126D01*
X204023Y403112D01*
X204009D01*
X203967D01*
X203910D01*
X203811Y403126D01*
X203713Y403140D01*
X203586Y403154D01*
X203445Y403182D01*
X203290Y403211D01*
X202966Y403309D01*
X202796Y403366D01*
X202613Y403450D01*
X202430Y403549D01*
X202261Y403648D01*
X202092Y403774D01*
X201922Y403915D01*
X201908Y403929D01*
X201880Y403958D01*
X201838Y404000D01*
X201796Y404071D01*
X201725Y404155D01*
X201655Y404268D01*
X201570Y404409D01*
X201500Y404564D01*
X201415Y404747D01*
X201330Y404959D01*
X201260Y405184D01*
X201203Y405452D01*
X201147Y405734D01*
X201105Y406044D01*
X201077Y406396D01*
X201063Y406763D01*
Y409258D01*
X197101D01*
Y410555D01*
X206856D01*
Y406552D01*
D02*
G37*
G36*
X204446Y401026D02*
X204474Y400997D01*
X204488Y400941D01*
X204530Y400871D01*
X204573Y400786D01*
X204629Y400687D01*
X204770Y400448D01*
X204925Y400166D01*
X205123Y399884D01*
X205348Y399588D01*
X205588Y399292D01*
X205602Y399277D01*
X205616Y399263D01*
X205658Y399221D01*
X205700Y399165D01*
X205841Y399038D01*
X206011Y398869D01*
X206208Y398699D01*
X206434Y398516D01*
X206659Y398361D01*
X206899Y398220D01*
Y397445D01*
X197101D01*
Y398643D01*
X204728D01*
X204714Y398657D01*
X204657Y398728D01*
X204573Y398812D01*
X204474Y398953D01*
X204347Y399108D01*
X204206Y399306D01*
X204051Y399531D01*
X203896Y399785D01*
Y399799D01*
X203882Y399813D01*
X203826Y399898D01*
X203755Y400039D01*
X203671Y400208D01*
X203572Y400405D01*
X203473Y400617D01*
X203375Y400828D01*
X203290Y401040D01*
X204446D01*
Y401026D01*
D02*
G37*
G36*
X207929Y370101D02*
X206730D01*
Y377728D01*
X206716Y377714D01*
X206646Y377657D01*
X206561Y377573D01*
X206420Y377474D01*
X206265Y377347D01*
X206068Y377206D01*
X205842Y377051D01*
X205589Y376896D01*
X205574D01*
X205560Y376882D01*
X205476Y376826D01*
X205335Y376755D01*
X205166Y376670D01*
X204968Y376572D01*
X204757Y376473D01*
X204545Y376375D01*
X204334Y376290D01*
Y377446D01*
X204348D01*
X204376Y377474D01*
X204433Y377488D01*
X204503Y377530D01*
X204588Y377573D01*
X204686Y377629D01*
X204926Y377770D01*
X205208Y377925D01*
X205490Y378122D01*
X205786Y378348D01*
X206082Y378588D01*
X206096Y378602D01*
X206110Y378616D01*
X206152Y378658D01*
X206209Y378700D01*
X206336Y378842D01*
X206505Y379011D01*
X206674Y379208D01*
X206857Y379434D01*
X207012Y379659D01*
X207153Y379899D01*
X207929D01*
Y370101D01*
D02*
G37*
G36*
X198075Y379842D02*
X198357Y379828D01*
X198639Y379800D01*
X198921Y379758D01*
X199160Y379715D01*
X199174D01*
X199203Y379701D01*
X199245D01*
X199301Y379673D01*
X199456Y379631D01*
X199654Y379560D01*
X199879Y379462D01*
X200119Y379335D01*
X200359Y379194D01*
X200584Y379011D01*
X200598Y378997D01*
X200612Y378982D01*
X200655Y378940D01*
X200711Y378898D01*
X200852Y378757D01*
X201021Y378559D01*
X201204Y378320D01*
X201402Y378038D01*
X201585Y377714D01*
X201740Y377347D01*
Y377333D01*
X201754Y377305D01*
X201782Y377248D01*
X201796Y377164D01*
X201839Y377065D01*
X201867Y376953D01*
X201895Y376826D01*
X201938Y376670D01*
X201980Y376516D01*
X202008Y376332D01*
X202078Y375938D01*
X202121Y375500D01*
X202135Y375021D01*
Y375007D01*
Y374979D01*
Y374908D01*
Y374838D01*
X202121Y374739D01*
Y374627D01*
X202107Y374359D01*
X202064Y374049D01*
X202022Y373724D01*
X201952Y373386D01*
X201867Y373048D01*
Y373033D01*
X201853Y373005D01*
X201839Y372963D01*
X201825Y372907D01*
X201768Y372752D01*
X201684Y372554D01*
X201599Y372329D01*
X201486Y372103D01*
X201345Y371863D01*
X201204Y371638D01*
X201190Y371610D01*
X201134Y371539D01*
X201049Y371441D01*
X200937Y371314D01*
X200810Y371173D01*
X200655Y371032D01*
X200500Y370877D01*
X200316Y370750D01*
X200288Y370736D01*
X200232Y370693D01*
X200133Y370637D01*
X199992Y370566D01*
X199823Y370482D01*
X199626Y370411D01*
X199400Y370327D01*
X199146Y370256D01*
X199118D01*
X199076Y370242D01*
X199034Y370228D01*
X198892Y370214D01*
X198695Y370186D01*
X198470Y370158D01*
X198202Y370130D01*
X197906Y370115D01*
X197582Y370101D01*
X194071D01*
Y379856D01*
X197821D01*
X198075Y379842D01*
D02*
G37*
G36*
X-14676Y383897D02*
X-14535D01*
X-14394Y383883D01*
X-14211Y383869D01*
X-14027Y383840D01*
X-13619Y383770D01*
X-13167Y383671D01*
X-12716Y383530D01*
X-12279Y383333D01*
X-12265Y383319D01*
X-12223Y383305D01*
X-12167Y383277D01*
X-12096Y383220D01*
X-11997Y383164D01*
X-11885Y383093D01*
X-11631Y382910D01*
X-11349Y382671D01*
X-11067Y382388D01*
X-10785Y382064D01*
X-10545Y381684D01*
X-10531Y381670D01*
X-10517Y381627D01*
X-10489Y381571D01*
X-10447Y381500D01*
X-10404Y381388D01*
X-10362Y381275D01*
X-10306Y381134D01*
X-10249Y380979D01*
X-10193Y380810D01*
X-10136Y380626D01*
X-10052Y380232D01*
X-9981Y379781D01*
X-9953Y379315D01*
Y379174D01*
X-9967Y379076D01*
X-9981Y378949D01*
X-9996Y378794D01*
X-10010Y378639D01*
X-10052Y378456D01*
X-10136Y378075D01*
X-10263Y377652D01*
X-10348Y377440D01*
X-10447Y377243D01*
X-10574Y377046D01*
X-10700Y376848D01*
X-10714Y376834D01*
X-10729Y376806D01*
X-10771Y376750D01*
X-10841Y376679D01*
X-10912Y376609D01*
X-11011Y376510D01*
X-11123Y376411D01*
X-11236Y376299D01*
X-11377Y376186D01*
X-11546Y376073D01*
X-11715Y375946D01*
X-11899Y375833D01*
X-12110Y375735D01*
X-12322Y375622D01*
X-12547Y375537D01*
X-12801Y375453D01*
X-13097Y376721D01*
X-13083D01*
X-13055Y376736D01*
X-12998Y376764D01*
X-12928Y376792D01*
X-12843Y376820D01*
X-12730Y376862D01*
X-12505Y376975D01*
X-12251Y377116D01*
X-11997Y377285D01*
X-11758Y377497D01*
X-11546Y377722D01*
X-11518Y377751D01*
X-11462Y377835D01*
X-11391Y377976D01*
X-11293Y378159D01*
X-11208Y378399D01*
X-11123Y378667D01*
X-11067Y378991D01*
X-11053Y379344D01*
Y379456D01*
X-11067Y379527D01*
Y379626D01*
X-11081Y379738D01*
X-11123Y380006D01*
X-11180Y380302D01*
X-11278Y380612D01*
X-11419Y380937D01*
X-11603Y381233D01*
Y381247D01*
X-11631Y381261D01*
X-11701Y381359D01*
X-11814Y381486D01*
X-11983Y381641D01*
X-12195Y381825D01*
X-12434Y381994D01*
X-12730Y382149D01*
X-13055Y382290D01*
X-13069D01*
X-13097Y382304D01*
X-13139Y382318D01*
X-13210Y382332D01*
X-13294Y382360D01*
X-13393Y382388D01*
X-13633Y382431D01*
X-13915Y382487D01*
X-14225Y382544D01*
X-14563Y382572D01*
X-14929Y382586D01*
X-14944D01*
X-14986D01*
X-15056D01*
X-15141D01*
X-15240Y382572D01*
X-15366D01*
X-15508Y382558D01*
X-15663Y382544D01*
X-16001Y382501D01*
X-16367Y382431D01*
X-16734Y382346D01*
X-17100Y382234D01*
X-17114D01*
X-17143Y382219D01*
X-17185Y382191D01*
X-17256Y382163D01*
X-17425Y382078D01*
X-17622Y381951D01*
X-17848Y381796D01*
X-18087Y381599D01*
X-18299Y381374D01*
X-18496Y381106D01*
Y381092D01*
X-18510Y381063D01*
X-18538Y381021D01*
X-18566Y380965D01*
X-18595Y380894D01*
X-18637Y380810D01*
X-18722Y380612D01*
X-18806Y380359D01*
X-18877Y380077D01*
X-18933Y379767D01*
X-18947Y379442D01*
Y379344D01*
X-18933Y379259D01*
Y379160D01*
X-18919Y379062D01*
X-18863Y378808D01*
X-18792Y378512D01*
X-18679Y378216D01*
X-18524Y377906D01*
X-18440Y377751D01*
X-18327Y377610D01*
X-18313Y377596D01*
X-18299Y377581D01*
X-18256Y377539D01*
X-18214Y377483D01*
X-18144Y377426D01*
X-18059Y377356D01*
X-17974Y377271D01*
X-17862Y377201D01*
X-17735Y377116D01*
X-17594Y377018D01*
X-17453Y376933D01*
X-17284Y376848D01*
X-17100Y376778D01*
X-16903Y376707D01*
X-16692Y376637D01*
X-16466Y376581D01*
X-16790Y375284D01*
X-16804D01*
X-16861Y375298D01*
X-16945Y375326D01*
X-17058Y375368D01*
X-17185Y375410D01*
X-17340Y375467D01*
X-17509Y375537D01*
X-17693Y375622D01*
X-18087Y375819D01*
X-18482Y376073D01*
X-18679Y376228D01*
X-18877Y376383D01*
X-19046Y376552D01*
X-19215Y376750D01*
X-19229Y376764D01*
X-19257Y376792D01*
X-19286Y376862D01*
X-19342Y376933D01*
X-19412Y377046D01*
X-19483Y377159D01*
X-19553Y377314D01*
X-19624Y377469D01*
X-19708Y377652D01*
X-19779Y377849D01*
X-19849Y378061D01*
X-19920Y378286D01*
X-19976Y378526D01*
X-20004Y378780D01*
X-20033Y379048D01*
X-20047Y379329D01*
Y379485D01*
X-20033Y379597D01*
Y379724D01*
X-20018Y379879D01*
X-19990Y380048D01*
X-19962Y380246D01*
X-19892Y380655D01*
X-19779Y381077D01*
X-19624Y381500D01*
X-19525Y381698D01*
X-19412Y381895D01*
X-19398Y381909D01*
X-19384Y381937D01*
X-19342Y381994D01*
X-19286Y382050D01*
X-19229Y382135D01*
X-19145Y382234D01*
X-19046Y382346D01*
X-18933Y382459D01*
X-18806Y382572D01*
X-18679Y382699D01*
X-18355Y382952D01*
X-17974Y383192D01*
X-17552Y383404D01*
X-17537D01*
X-17495Y383432D01*
X-17425Y383446D01*
X-17340Y383488D01*
X-17227Y383516D01*
X-17086Y383559D01*
X-16931Y383615D01*
X-16762Y383657D01*
X-16579Y383700D01*
X-16367Y383756D01*
X-15930Y383826D01*
X-15437Y383883D01*
X-14929Y383911D01*
X-14915D01*
X-14859D01*
X-14774D01*
X-14676Y383897D01*
D02*
G37*
G36*
X-12533Y373254D02*
X-12505Y373226D01*
X-12491Y373169D01*
X-12448Y373099D01*
X-12406Y373014D01*
X-12350Y372915D01*
X-12209Y372676D01*
X-12054Y372394D01*
X-11856Y372112D01*
X-11631Y371816D01*
X-11391Y371520D01*
X-11377Y371506D01*
X-11363Y371492D01*
X-11321Y371449D01*
X-11278Y371393D01*
X-11137Y371266D01*
X-10968Y371097D01*
X-10771Y370928D01*
X-10545Y370744D01*
X-10320Y370589D01*
X-10080Y370448D01*
Y369673D01*
X-19878D01*
Y370871D01*
X-12251D01*
X-12265Y370885D01*
X-12322Y370956D01*
X-12406Y371040D01*
X-12505Y371181D01*
X-12632Y371337D01*
X-12773Y371534D01*
X-12928Y371759D01*
X-13083Y372013D01*
Y372027D01*
X-13097Y372041D01*
X-13153Y372126D01*
X-13224Y372267D01*
X-13308Y372436D01*
X-13407Y372633D01*
X-13506Y372845D01*
X-13604Y373056D01*
X-13689Y373268D01*
X-12533D01*
Y373254D01*
D02*
G37*
G36*
Y365670D02*
X-12505Y365641D01*
X-12491Y365585D01*
X-12448Y365514D01*
X-12406Y365430D01*
X-12350Y365331D01*
X-12209Y365092D01*
X-12054Y364810D01*
X-11856Y364528D01*
X-11631Y364232D01*
X-11391Y363936D01*
X-11377Y363922D01*
X-11363Y363907D01*
X-11321Y363865D01*
X-11278Y363809D01*
X-11137Y363682D01*
X-10968Y363513D01*
X-10771Y363344D01*
X-10545Y363160D01*
X-10320Y363005D01*
X-10080Y362864D01*
Y362089D01*
X-19878D01*
Y363287D01*
X-12251D01*
X-12265Y363301D01*
X-12322Y363372D01*
X-12406Y363456D01*
X-12505Y363597D01*
X-12632Y363752D01*
X-12773Y363950D01*
X-12928Y364175D01*
X-13083Y364429D01*
Y364443D01*
X-13097Y364457D01*
X-13153Y364542D01*
X-13224Y364683D01*
X-13308Y364852D01*
X-13407Y365049D01*
X-13506Y365261D01*
X-13604Y365472D01*
X-13689Y365684D01*
X-12533D01*
Y365670D01*
D02*
G37*
G36*
X199324Y358827D02*
X199465D01*
X199606Y358813D01*
X199789Y358799D01*
X199973Y358771D01*
X200382Y358700D01*
X200833Y358602D01*
X201284Y358461D01*
X201721Y358264D01*
X201735Y358249D01*
X201777Y358235D01*
X201833Y358207D01*
X201904Y358151D01*
X202003Y358094D01*
X202115Y358024D01*
X202369Y357841D01*
X202651Y357601D01*
X202933Y357319D01*
X203215Y356995D01*
X203455Y356614D01*
X203469Y356600D01*
X203483Y356558D01*
X203511Y356501D01*
X203553Y356431D01*
X203596Y356318D01*
X203638Y356205D01*
X203694Y356064D01*
X203751Y355909D01*
X203807Y355740D01*
X203863Y355557D01*
X203948Y355162D01*
X204018Y354711D01*
X204047Y354246D01*
Y354105D01*
X204033Y354006D01*
X204018Y353879D01*
X204004Y353724D01*
X203990Y353569D01*
X203948Y353386D01*
X203863Y353005D01*
X203737Y352582D01*
X203652Y352371D01*
X203553Y352174D01*
X203426Y351976D01*
X203300Y351779D01*
X203286Y351765D01*
X203271Y351737D01*
X203229Y351680D01*
X203159Y351610D01*
X203088Y351539D01*
X202989Y351441D01*
X202877Y351342D01*
X202764Y351229D01*
X202623Y351116D01*
X202454Y351003D01*
X202285Y350877D01*
X202101Y350764D01*
X201890Y350665D01*
X201678Y350552D01*
X201453Y350468D01*
X201199Y350383D01*
X200903Y351652D01*
X200917D01*
X200945Y351666D01*
X201002Y351694D01*
X201072Y351722D01*
X201157Y351751D01*
X201270Y351793D01*
X201495Y351906D01*
X201749Y352047D01*
X202003Y352216D01*
X202242Y352427D01*
X202454Y352653D01*
X202482Y352681D01*
X202538Y352766D01*
X202609Y352907D01*
X202708Y353090D01*
X202792Y353330D01*
X202877Y353597D01*
X202933Y353922D01*
X202947Y354274D01*
Y354387D01*
X202933Y354457D01*
Y354556D01*
X202919Y354669D01*
X202877Y354937D01*
X202820Y355233D01*
X202722Y355543D01*
X202581Y355867D01*
X202397Y356163D01*
Y356177D01*
X202369Y356191D01*
X202299Y356290D01*
X202186Y356417D01*
X202017Y356572D01*
X201805Y356755D01*
X201566Y356924D01*
X201270Y357079D01*
X200945Y357220D01*
X200931D01*
X200903Y357234D01*
X200861Y357248D01*
X200790Y357263D01*
X200706Y357291D01*
X200607Y357319D01*
X200367Y357361D01*
X200086Y357418D01*
X199775Y357474D01*
X199437Y357502D01*
X199070Y357516D01*
X199056D01*
X199014D01*
X198944D01*
X198859D01*
X198760Y357502D01*
X198633D01*
X198493Y357488D01*
X198337Y357474D01*
X197999Y357432D01*
X197633Y357361D01*
X197266Y357277D01*
X196900Y357164D01*
X196885D01*
X196857Y357150D01*
X196815Y357122D01*
X196744Y357093D01*
X196575Y357009D01*
X196378Y356882D01*
X196152Y356727D01*
X195913Y356530D01*
X195701Y356304D01*
X195504Y356036D01*
Y356022D01*
X195490Y355994D01*
X195462Y355952D01*
X195433Y355895D01*
X195405Y355825D01*
X195363Y355740D01*
X195278Y355543D01*
X195194Y355289D01*
X195123Y355007D01*
X195067Y354697D01*
X195053Y354373D01*
Y354274D01*
X195067Y354189D01*
Y354091D01*
X195081Y353992D01*
X195137Y353738D01*
X195208Y353442D01*
X195321Y353146D01*
X195476Y352836D01*
X195560Y352681D01*
X195673Y352540D01*
X195687Y352526D01*
X195701Y352512D01*
X195744Y352470D01*
X195786Y352413D01*
X195856Y352357D01*
X195941Y352286D01*
X196026Y352202D01*
X196138Y352131D01*
X196265Y352047D01*
X196406Y351948D01*
X196547Y351863D01*
X196716Y351779D01*
X196900Y351708D01*
X197097Y351638D01*
X197308Y351567D01*
X197534Y351511D01*
X197210Y350214D01*
X197196D01*
X197139Y350228D01*
X197055Y350256D01*
X196942Y350299D01*
X196815Y350341D01*
X196660Y350397D01*
X196491Y350468D01*
X196308Y350552D01*
X195913Y350750D01*
X195518Y351003D01*
X195321Y351159D01*
X195123Y351314D01*
X194954Y351483D01*
X194785Y351680D01*
X194771Y351694D01*
X194743Y351722D01*
X194715Y351793D01*
X194658Y351863D01*
X194588Y351976D01*
X194517Y352089D01*
X194447Y352244D01*
X194376Y352399D01*
X194292Y352582D01*
X194221Y352780D01*
X194151Y352991D01*
X194080Y353217D01*
X194024Y353456D01*
X193995Y353710D01*
X193967Y353978D01*
X193953Y354260D01*
Y354415D01*
X193967Y354528D01*
Y354655D01*
X193981Y354810D01*
X194010Y354979D01*
X194038Y355176D01*
X194108Y355585D01*
X194221Y356008D01*
X194376Y356431D01*
X194475Y356628D01*
X194588Y356826D01*
X194602Y356840D01*
X194616Y356868D01*
X194658Y356924D01*
X194715Y356981D01*
X194771Y357065D01*
X194855Y357164D01*
X194954Y357277D01*
X195067Y357389D01*
X195194Y357502D01*
X195321Y357629D01*
X195645Y357883D01*
X196026Y358122D01*
X196448Y358334D01*
X196462D01*
X196505Y358362D01*
X196575Y358376D01*
X196660Y358419D01*
X196773Y358447D01*
X196914Y358489D01*
X197069Y358545D01*
X197238Y358588D01*
X197421Y358630D01*
X197633Y358686D01*
X198070Y358757D01*
X198563Y358813D01*
X199070Y358841D01*
X199085D01*
X199141D01*
X199226D01*
X199324Y358827D01*
D02*
G37*
G36*
X201467Y348184D02*
X201495Y348156D01*
X201509Y348100D01*
X201551Y348029D01*
X201594Y347944D01*
X201650Y347846D01*
X201791Y347606D01*
X201946Y347324D01*
X202144Y347042D01*
X202369Y346746D01*
X202609Y346450D01*
X202623Y346436D01*
X202637Y346422D01*
X202679Y346380D01*
X202722Y346323D01*
X202863Y346196D01*
X203032Y346027D01*
X203229Y345858D01*
X203455Y345675D01*
X203680Y345520D01*
X203920Y345379D01*
Y344604D01*
X194122D01*
Y345802D01*
X201749D01*
X201735Y345816D01*
X201678Y345886D01*
X201594Y345971D01*
X201495Y346112D01*
X201368Y346267D01*
X201227Y346464D01*
X201072Y346690D01*
X200917Y346944D01*
Y346958D01*
X200903Y346972D01*
X200847Y347056D01*
X200776Y347197D01*
X200692Y347366D01*
X200593Y347564D01*
X200494Y347775D01*
X200396Y347987D01*
X200311Y348198D01*
X201467D01*
Y348184D01*
D02*
G37*
G36*
X199366Y341516D02*
X199536D01*
X199719Y341502D01*
X199930Y341488D01*
X200367Y341446D01*
X200833Y341375D01*
X201298Y341291D01*
X201509Y341234D01*
X201721Y341178D01*
X201735D01*
X201763Y341164D01*
X201819Y341136D01*
X201890Y341107D01*
X201989Y341079D01*
X202087Y341023D01*
X202327Y340910D01*
X202581Y340769D01*
X202848Y340586D01*
X203116Y340374D01*
X203342Y340121D01*
Y340107D01*
X203370Y340092D01*
X203398Y340050D01*
X203426Y339994D01*
X203483Y339923D01*
X203525Y339839D01*
X203638Y339627D01*
X203737Y339374D01*
X203835Y339077D01*
X203892Y338725D01*
X203920Y338344D01*
Y338218D01*
X203906Y338063D01*
X203878Y337879D01*
X203835Y337668D01*
X203779Y337442D01*
X203708Y337203D01*
X203596Y336977D01*
Y336963D01*
X203582Y336949D01*
X203539Y336878D01*
X203469Y336766D01*
X203370Y336625D01*
X203229Y336469D01*
X203074Y336300D01*
X202891Y336145D01*
X202679Y335990D01*
X202651Y335976D01*
X202581Y335920D01*
X202454Y335863D01*
X202271Y335765D01*
X202059Y335680D01*
X201819Y335567D01*
X201537Y335469D01*
X201227Y335384D01*
X201213D01*
X201185Y335370D01*
X201143Y335356D01*
X201072Y335342D01*
X200988Y335328D01*
X200889Y335314D01*
X200762Y335285D01*
X200621Y335271D01*
X200466Y335243D01*
X200297Y335229D01*
X200100Y335215D01*
X199902Y335187D01*
X199677Y335173D01*
X199451D01*
X199197Y335159D01*
X198930D01*
X198915D01*
X198859D01*
X198760D01*
X198648D01*
X198493Y335173D01*
X198323D01*
X198140Y335187D01*
X197943Y335201D01*
X197492Y335243D01*
X197026Y335314D01*
X196575Y335398D01*
X196364Y335454D01*
X196152Y335525D01*
X196138D01*
X196110Y335539D01*
X196054Y335567D01*
X195983Y335596D01*
X195884Y335624D01*
X195786Y335680D01*
X195546Y335793D01*
X195292Y335934D01*
X195011Y336117D01*
X194757Y336329D01*
X194517Y336582D01*
Y336596D01*
X194489Y336610D01*
X194461Y336653D01*
X194433Y336709D01*
X194390Y336780D01*
X194334Y336850D01*
X194235Y337062D01*
X194137Y337315D01*
X194038Y337611D01*
X193981Y337964D01*
X193953Y338344D01*
Y338485D01*
X193967Y338584D01*
X193981Y338697D01*
X194010Y338838D01*
X194038Y338993D01*
X194080Y339162D01*
X194137Y339331D01*
X194193Y339515D01*
X194277Y339698D01*
X194376Y339881D01*
X194489Y340064D01*
X194630Y340247D01*
X194785Y340417D01*
X194954Y340572D01*
X194968Y340586D01*
X195011Y340614D01*
X195081Y340656D01*
X195194Y340727D01*
X195321Y340797D01*
X195490Y340868D01*
X195687Y340966D01*
X195913Y341051D01*
X196166Y341136D01*
X196462Y341220D01*
X196787Y341305D01*
X197153Y341375D01*
X197548Y341446D01*
X197971Y341488D01*
X198436Y341516D01*
X198930Y341530D01*
X198944D01*
X199000D01*
X199099D01*
X199211D01*
X199366Y341516D01*
D02*
G37*
G36*
X5765Y414910D02*
X5892Y414896D01*
X6047Y414882D01*
X6202Y414868D01*
X6385Y414826D01*
X6766Y414741D01*
X7189Y414614D01*
X7400Y414530D01*
X7597Y414431D01*
X7795Y414304D01*
X7992Y414177D01*
X8006Y414163D01*
X8034Y414149D01*
X8091Y414107D01*
X8161Y414036D01*
X8232Y413966D01*
X8330Y413867D01*
X8429Y413755D01*
X8542Y413642D01*
X8655Y413501D01*
X8767Y413332D01*
X8894Y413162D01*
X9007Y412979D01*
X9106Y412768D01*
X9219Y412556D01*
X9303Y412331D01*
X9388Y412077D01*
X8119Y411781D01*
Y411795D01*
X8105Y411823D01*
X8077Y411880D01*
X8048Y411950D01*
X8020Y412035D01*
X7978Y412147D01*
X7865Y412373D01*
X7724Y412627D01*
X7555Y412881D01*
X7344Y413120D01*
X7118Y413332D01*
X7090Y413360D01*
X7005Y413416D01*
X6864Y413487D01*
X6681Y413585D01*
X6441Y413670D01*
X6174Y413755D01*
X5849Y413811D01*
X5497Y413825D01*
X5384D01*
X5314Y413811D01*
X5215D01*
X5102Y413797D01*
X4834Y413755D01*
X4538Y413698D01*
X4228Y413599D01*
X3904Y413459D01*
X3608Y413275D01*
X3594D01*
X3580Y413247D01*
X3481Y413176D01*
X3354Y413064D01*
X3199Y412895D01*
X3016Y412683D01*
X2847Y412444D01*
X2692Y412147D01*
X2551Y411823D01*
Y411809D01*
X2537Y411781D01*
X2522Y411739D01*
X2508Y411668D01*
X2480Y411584D01*
X2452Y411485D01*
X2410Y411245D01*
X2353Y410963D01*
X2297Y410653D01*
X2269Y410315D01*
X2255Y409948D01*
Y409934D01*
Y409892D01*
Y409821D01*
Y409737D01*
X2269Y409638D01*
Y409511D01*
X2283Y409370D01*
X2297Y409215D01*
X2339Y408877D01*
X2410Y408510D01*
X2494Y408144D01*
X2607Y407777D01*
Y407763D01*
X2621Y407735D01*
X2649Y407693D01*
X2677Y407622D01*
X2762Y407453D01*
X2889Y407256D01*
X3044Y407030D01*
X3241Y406791D01*
X3467Y406579D01*
X3735Y406382D01*
X3749D01*
X3777Y406368D01*
X3819Y406339D01*
X3876Y406311D01*
X3946Y406283D01*
X4031Y406241D01*
X4228Y406156D01*
X4482Y406072D01*
X4764Y406001D01*
X5074Y405945D01*
X5398Y405931D01*
X5497D01*
X5581Y405945D01*
X5680D01*
X5779Y405959D01*
X6033Y406015D01*
X6329Y406086D01*
X6625Y406199D01*
X6935Y406354D01*
X7090Y406438D01*
X7231Y406551D01*
X7245Y406565D01*
X7259Y406579D01*
X7301Y406621D01*
X7358Y406664D01*
X7414Y406734D01*
X7485Y406819D01*
X7569Y406903D01*
X7640Y407016D01*
X7724Y407143D01*
X7823Y407284D01*
X7908Y407425D01*
X7992Y407594D01*
X8063Y407777D01*
X8133Y407975D01*
X8203Y408186D01*
X8260Y408412D01*
X9557Y408088D01*
Y408073D01*
X9543Y408017D01*
X9515Y407932D01*
X9472Y407820D01*
X9430Y407693D01*
X9374Y407538D01*
X9303Y407369D01*
X9219Y407185D01*
X9021Y406791D01*
X8767Y406396D01*
X8612Y406199D01*
X8457Y406001D01*
X8288Y405832D01*
X8091Y405663D01*
X8077Y405649D01*
X8048Y405620D01*
X7978Y405592D01*
X7908Y405536D01*
X7795Y405466D01*
X7682Y405395D01*
X7527Y405325D01*
X7372Y405254D01*
X7189Y405169D01*
X6991Y405099D01*
X6780Y405028D01*
X6554Y404958D01*
X6314Y404902D01*
X6061Y404873D01*
X5793Y404845D01*
X5511Y404831D01*
X5356D01*
X5243Y404845D01*
X5116D01*
X4961Y404859D01*
X4792Y404888D01*
X4595Y404916D01*
X4186Y404986D01*
X3763Y405099D01*
X3340Y405254D01*
X3143Y405353D01*
X2945Y405466D01*
X2931Y405480D01*
X2903Y405494D01*
X2847Y405536D01*
X2790Y405592D01*
X2706Y405649D01*
X2607Y405733D01*
X2494Y405832D01*
X2382Y405945D01*
X2269Y406072D01*
X2142Y406199D01*
X1888Y406523D01*
X1648Y406903D01*
X1437Y407326D01*
Y407340D01*
X1409Y407383D01*
X1395Y407453D01*
X1352Y407538D01*
X1324Y407650D01*
X1282Y407791D01*
X1226Y407947D01*
X1183Y408116D01*
X1141Y408299D01*
X1085Y408510D01*
X1014Y408947D01*
X958Y409441D01*
X930Y409948D01*
Y409962D01*
Y410019D01*
Y410103D01*
X944Y410202D01*
Y410343D01*
X958Y410484D01*
X972Y410667D01*
X1000Y410850D01*
X1071Y411259D01*
X1169Y411710D01*
X1310Y412161D01*
X1507Y412598D01*
X1522Y412613D01*
X1536Y412655D01*
X1564Y412711D01*
X1620Y412782D01*
X1677Y412881D01*
X1747Y412993D01*
X1930Y413247D01*
X2170Y413529D01*
X2452Y413811D01*
X2776Y414093D01*
X3157Y414333D01*
X3171Y414347D01*
X3213Y414361D01*
X3270Y414389D01*
X3340Y414431D01*
X3453Y414473D01*
X3566Y414516D01*
X3707Y414572D01*
X3862Y414628D01*
X4031Y414685D01*
X4214Y414741D01*
X4609Y414826D01*
X5060Y414896D01*
X5525Y414925D01*
X5666D01*
X5765Y414910D01*
D02*
G37*
G36*
X13885Y414784D02*
X13955D01*
X14054Y414770D01*
X14293Y414727D01*
X14561Y414671D01*
X14857Y414572D01*
X15153Y414445D01*
X15449Y414276D01*
X15464D01*
X15478Y414248D01*
X15520Y414220D01*
X15576Y414177D01*
X15717Y414065D01*
X15900Y413910D01*
X16084Y413698D01*
X16295Y413444D01*
X16479Y413148D01*
X16648Y412810D01*
Y412796D01*
X16662Y412768D01*
X16690Y412711D01*
X16718Y412641D01*
X16746Y412542D01*
X16789Y412415D01*
X16817Y412274D01*
X16859Y412119D01*
X16901Y411936D01*
X16944Y411725D01*
X16972Y411499D01*
X17000Y411259D01*
X17028Y410992D01*
X17056Y410709D01*
X17071Y410399D01*
Y410075D01*
Y410061D01*
Y409991D01*
Y409892D01*
Y409765D01*
X17056Y409610D01*
Y409427D01*
X17042Y409215D01*
X17014Y409004D01*
X16972Y408525D01*
X16901Y408017D01*
X16803Y407538D01*
X16732Y407298D01*
X16662Y407087D01*
Y407072D01*
X16648Y407044D01*
X16619Y406988D01*
X16591Y406903D01*
X16549Y406819D01*
X16493Y406706D01*
X16352Y406466D01*
X16182Y406199D01*
X15985Y405917D01*
X15731Y405649D01*
X15449Y405409D01*
X15435D01*
X15407Y405381D01*
X15365Y405353D01*
X15308Y405325D01*
X15224Y405282D01*
X15139Y405226D01*
X15027Y405169D01*
X14914Y405127D01*
X14646Y405014D01*
X14322Y404916D01*
X13969Y404859D01*
X13575Y404831D01*
X13462D01*
X13391Y404845D01*
X13293D01*
X13180Y404859D01*
X12912Y404916D01*
X12616Y404986D01*
X12306Y405099D01*
X11996Y405254D01*
X11841Y405353D01*
X11700Y405466D01*
X11686Y405480D01*
X11671Y405494D01*
X11629Y405536D01*
X11587Y405578D01*
X11530Y405649D01*
X11460Y405733D01*
X11319Y405931D01*
X11178Y406184D01*
X11037Y406494D01*
X10924Y406847D01*
X10840Y407256D01*
X11996Y407355D01*
Y407340D01*
X12010Y407312D01*
Y407284D01*
X12024Y407228D01*
X12066Y407072D01*
X12122Y406903D01*
X12193Y406706D01*
X12292Y406509D01*
X12404Y406325D01*
X12545Y406170D01*
X12559Y406156D01*
X12616Y406114D01*
X12715Y406058D01*
X12827Y406001D01*
X12982Y405931D01*
X13166Y405874D01*
X13377Y405832D01*
X13603Y405818D01*
X13701D01*
X13800Y405832D01*
X13927Y405846D01*
X14082Y405874D01*
X14237Y405917D01*
X14406Y405973D01*
X14561Y406058D01*
X14575Y406072D01*
X14632Y406100D01*
X14716Y406156D01*
X14801Y406241D01*
X14914Y406339D01*
X15027Y406452D01*
X15139Y406579D01*
X15252Y406734D01*
X15266Y406748D01*
X15294Y406819D01*
X15351Y406917D01*
X15407Y407044D01*
X15478Y407214D01*
X15548Y407411D01*
X15619Y407636D01*
X15689Y407890D01*
Y407904D01*
X15703Y407918D01*
Y407961D01*
X15717Y408017D01*
X15745Y408158D01*
X15788Y408341D01*
X15816Y408567D01*
X15844Y408806D01*
X15858Y409074D01*
X15872Y409356D01*
Y409370D01*
Y409413D01*
Y409483D01*
Y409596D01*
X15858Y409568D01*
X15802Y409497D01*
X15717Y409398D01*
X15619Y409258D01*
X15478Y409117D01*
X15308Y408961D01*
X15111Y408806D01*
X14885Y408666D01*
X14857Y408651D01*
X14773Y408609D01*
X14646Y408553D01*
X14491Y408496D01*
X14279Y408426D01*
X14054Y408369D01*
X13800Y408327D01*
X13532Y408313D01*
X13419D01*
X13335Y408327D01*
X13222Y408341D01*
X13109Y408355D01*
X12968Y408383D01*
X12827Y408426D01*
X12503Y408525D01*
X12334Y408595D01*
X12165Y408680D01*
X11982Y408778D01*
X11812Y408905D01*
X11643Y409032D01*
X11488Y409187D01*
X11474Y409201D01*
X11446Y409229D01*
X11418Y409272D01*
X11361Y409342D01*
X11291Y409441D01*
X11220Y409539D01*
X11150Y409666D01*
X11079Y409807D01*
X10995Y409962D01*
X10924Y410132D01*
X10854Y410329D01*
X10783Y410526D01*
X10727Y410752D01*
X10699Y410992D01*
X10670Y411231D01*
X10656Y411499D01*
Y411513D01*
Y411570D01*
Y411640D01*
X10670Y411739D01*
X10685Y411866D01*
X10699Y412021D01*
X10727Y412176D01*
X10769Y412359D01*
X10868Y412725D01*
X10938Y412923D01*
X11023Y413134D01*
X11122Y413332D01*
X11249Y413515D01*
X11375Y413712D01*
X11530Y413881D01*
X11545Y413895D01*
X11573Y413924D01*
X11615Y413966D01*
X11686Y414022D01*
X11770Y414093D01*
X11883Y414177D01*
X11996Y414248D01*
X12137Y414347D01*
X12278Y414431D01*
X12447Y414502D01*
X12827Y414657D01*
X13025Y414713D01*
X13250Y414755D01*
X13476Y414784D01*
X13715Y414798D01*
X13814D01*
X13885Y414784D01*
D02*
G37*
G36*
X139447Y390480D02*
X139496D01*
X139552Y390473D01*
X139686Y390445D01*
X139834Y390410D01*
X139988Y390354D01*
X140143Y390269D01*
X140221Y390220D01*
X140291Y390163D01*
X140298Y390157D01*
X140305Y390149D01*
X140326Y390128D01*
X140347Y390107D01*
X140382Y390072D01*
X140410Y390030D01*
X140488Y389931D01*
X140565Y389805D01*
X140636Y389650D01*
X140699Y389474D01*
X140741Y389277D01*
X140143Y389228D01*
Y389235D01*
X140136Y389242D01*
X140129Y389284D01*
X140108Y389347D01*
X140080Y389425D01*
X140052Y389509D01*
X140009Y389594D01*
X139960Y389671D01*
X139911Y389734D01*
X139897Y389748D01*
X139869Y389777D01*
X139819Y389819D01*
X139749Y389868D01*
X139658Y389910D01*
X139559Y389953D01*
X139440Y389981D01*
X139313Y389995D01*
X139264D01*
X139207Y389988D01*
X139144Y389974D01*
X139060Y389953D01*
X138975Y389924D01*
X138891Y389889D01*
X138806Y389833D01*
X138792Y389826D01*
X138757Y389798D01*
X138708Y389748D01*
X138645Y389678D01*
X138574Y389594D01*
X138497Y389495D01*
X138426Y389369D01*
X138356Y389228D01*
Y389221D01*
X138349Y389207D01*
X138342Y389186D01*
X138328Y389157D01*
X138321Y389115D01*
X138307Y389066D01*
X138293Y389010D01*
X138279Y388939D01*
X138258Y388862D01*
X138244Y388778D01*
X138229Y388686D01*
X138222Y388587D01*
X138208Y388475D01*
X138201Y388362D01*
X138194Y388236D01*
Y388109D01*
X138201Y388116D01*
X138229Y388158D01*
X138279Y388215D01*
X138342Y388285D01*
X138412Y388369D01*
X138504Y388447D01*
X138602Y388524D01*
X138715Y388595D01*
X138722D01*
X138729Y388602D01*
X138771Y388623D01*
X138834Y388644D01*
X138919Y388679D01*
X139017Y388707D01*
X139130Y388728D01*
X139250Y388749D01*
X139376Y388756D01*
X139433D01*
X139475Y388749D01*
X139531Y388742D01*
X139587Y388735D01*
X139658Y388721D01*
X139728Y388700D01*
X139890Y388651D01*
X139974Y388616D01*
X140059Y388566D01*
X140143Y388517D01*
X140235Y388461D01*
X140319Y388391D01*
X140396Y388313D01*
X140403Y388306D01*
X140418Y388292D01*
X140439Y388271D01*
X140460Y388236D01*
X140495Y388186D01*
X140530Y388137D01*
X140565Y388074D01*
X140608Y388004D01*
X140650Y387926D01*
X140685Y387842D01*
X140720Y387743D01*
X140755Y387645D01*
X140776Y387539D01*
X140798Y387420D01*
X140812Y387300D01*
X140819Y387173D01*
Y387166D01*
Y387152D01*
Y387131D01*
Y387096D01*
X140812Y387054D01*
Y387011D01*
X140791Y386899D01*
X140769Y386765D01*
X140734Y386624D01*
X140685Y386470D01*
X140615Y386322D01*
Y386315D01*
X140608Y386308D01*
X140594Y386287D01*
X140579Y386259D01*
X140537Y386188D01*
X140474Y386097D01*
X140396Y385998D01*
X140305Y385900D01*
X140192Y385801D01*
X140073Y385717D01*
X140066D01*
X140059Y385710D01*
X140038Y385696D01*
X140009Y385689D01*
X139939Y385654D01*
X139848Y385618D01*
X139728Y385576D01*
X139594Y385548D01*
X139447Y385520D01*
X139285Y385513D01*
X139250D01*
X139214Y385520D01*
X139158D01*
X139095Y385527D01*
X139024Y385541D01*
X138940Y385562D01*
X138856Y385583D01*
X138757Y385611D01*
X138659Y385647D01*
X138560Y385689D01*
X138455Y385745D01*
X138356Y385808D01*
X138258Y385879D01*
X138159Y385963D01*
X138068Y386062D01*
X138061Y386069D01*
X138047Y386090D01*
X138025Y386118D01*
X137997Y386167D01*
X137955Y386231D01*
X137920Y386301D01*
X137878Y386392D01*
X137835Y386491D01*
X137786Y386610D01*
X137744Y386744D01*
X137709Y386892D01*
X137674Y387054D01*
X137638Y387237D01*
X137617Y387434D01*
X137603Y387645D01*
X137596Y387870D01*
Y387877D01*
Y387884D01*
Y387905D01*
Y387933D01*
X137603Y388004D01*
Y388102D01*
X137610Y388215D01*
X137624Y388348D01*
X137638Y388496D01*
X137660Y388658D01*
X137688Y388820D01*
X137723Y388996D01*
X137765Y389164D01*
X137814Y389333D01*
X137878Y389495D01*
X137948Y389650D01*
X138025Y389798D01*
X138117Y389924D01*
X138124Y389931D01*
X138138Y389945D01*
X138166Y389974D01*
X138201Y390016D01*
X138244Y390058D01*
X138300Y390100D01*
X138370Y390157D01*
X138441Y390206D01*
X138525Y390255D01*
X138616Y390311D01*
X138722Y390354D01*
X138827Y390403D01*
X138947Y390438D01*
X139074Y390466D01*
X139207Y390480D01*
X139348Y390487D01*
X139404D01*
X139447Y390480D01*
D02*
G37*
G36*
X136091Y385597D02*
X135492D01*
Y389404D01*
X135485Y389397D01*
X135450Y389369D01*
X135408Y389326D01*
X135338Y389277D01*
X135260Y389214D01*
X135162Y389143D01*
X135049Y389066D01*
X134923Y388989D01*
X134916D01*
X134909Y388982D01*
X134866Y388953D01*
X134796Y388918D01*
X134712Y388876D01*
X134613Y388827D01*
X134508Y388778D01*
X134402Y388728D01*
X134296Y388686D01*
Y389263D01*
X134304D01*
X134318Y389277D01*
X134346Y389284D01*
X134381Y389305D01*
X134423Y389326D01*
X134472Y389354D01*
X134592Y389425D01*
X134733Y389502D01*
X134873Y389601D01*
X135021Y389713D01*
X135169Y389833D01*
X135176Y389840D01*
X135183Y389847D01*
X135204Y389868D01*
X135232Y389889D01*
X135295Y389959D01*
X135380Y390044D01*
X135464Y390142D01*
X135556Y390255D01*
X135633Y390368D01*
X135704Y390487D01*
X136091D01*
Y385597D01*
D02*
G37*
G36*
X131496Y390459D02*
X131559D01*
X131707Y390452D01*
X131862Y390431D01*
X132031Y390410D01*
X132186Y390375D01*
X132263Y390354D01*
X132326Y390332D01*
X132333D01*
X132340Y390325D01*
X132383Y390304D01*
X132446Y390276D01*
X132523Y390227D01*
X132608Y390163D01*
X132699Y390079D01*
X132784Y389981D01*
X132868Y389868D01*
Y389861D01*
X132875Y389854D01*
X132903Y389812D01*
X132931Y389741D01*
X132974Y389650D01*
X133009Y389544D01*
X133044Y389418D01*
X133065Y389284D01*
X133072Y389136D01*
Y389129D01*
Y389115D01*
Y389087D01*
X133065Y389052D01*
Y389003D01*
X133058Y388953D01*
X133030Y388834D01*
X132988Y388693D01*
X132931Y388545D01*
X132847Y388397D01*
X132791Y388327D01*
X132734Y388257D01*
X132727Y388250D01*
X132720Y388243D01*
X132699Y388222D01*
X132671Y388200D01*
X132636Y388172D01*
X132594Y388144D01*
X132537Y388109D01*
X132481Y388067D01*
X132411Y388032D01*
X132333Y387996D01*
X132249Y387954D01*
X132157Y387919D01*
X132052Y387891D01*
X131946Y387856D01*
X131827Y387835D01*
X131700Y387814D01*
X131714Y387807D01*
X131742Y387793D01*
X131785Y387764D01*
X131841Y387736D01*
X131968Y387659D01*
X132031Y387609D01*
X132087Y387567D01*
X132101Y387553D01*
X132136Y387518D01*
X132193Y387462D01*
X132263Y387391D01*
X132340Y387293D01*
X132432Y387187D01*
X132523Y387061D01*
X132622Y386920D01*
X133459Y385597D01*
X132657D01*
X132017Y386610D01*
Y386618D01*
X132003Y386632D01*
X131989Y386653D01*
X131968Y386681D01*
X131918Y386758D01*
X131855Y386857D01*
X131778Y386962D01*
X131700Y387075D01*
X131623Y387180D01*
X131552Y387279D01*
X131545Y387286D01*
X131524Y387314D01*
X131489Y387356D01*
X131440Y387406D01*
X131334Y387511D01*
X131278Y387560D01*
X131222Y387603D01*
X131215Y387609D01*
X131201Y387617D01*
X131173Y387631D01*
X131130Y387652D01*
X131088Y387673D01*
X131039Y387694D01*
X130926Y387729D01*
X130919D01*
X130905Y387736D01*
X130877D01*
X130842Y387743D01*
X130793Y387750D01*
X130736D01*
X130659Y387757D01*
X129829D01*
Y385597D01*
X129181D01*
Y390466D01*
X131440D01*
X131496Y390459D01*
D02*
G37*
G36*
X104869Y100829D02*
X104925Y100822D01*
X104988Y100815D01*
X105066Y100801D01*
X105143Y100787D01*
X105326Y100745D01*
X105516Y100674D01*
X105615Y100632D01*
X105706Y100576D01*
X105805Y100520D01*
X105896Y100449D01*
X105903Y100442D01*
X105924Y100428D01*
X105952Y100400D01*
X105988Y100365D01*
X106030Y100316D01*
X106086Y100259D01*
X106135Y100189D01*
X106192Y100112D01*
X106248Y100027D01*
X106297Y99929D01*
X106346Y99823D01*
X106396Y99711D01*
X106431Y99591D01*
X106459Y99457D01*
X106480Y99317D01*
X106487Y99169D01*
Y99105D01*
X106480Y99056D01*
X106473Y99000D01*
X106466Y98937D01*
X106459Y98859D01*
X106438Y98782D01*
X106396Y98606D01*
X106332Y98430D01*
X106290Y98338D01*
X106241Y98247D01*
X106185Y98163D01*
X106121Y98078D01*
X106114Y98071D01*
X106107Y98057D01*
X106079Y98043D01*
X106051Y98015D01*
X106016Y97980D01*
X105974Y97944D01*
X105917Y97902D01*
X105854Y97867D01*
X105791Y97825D01*
X105713Y97783D01*
X105544Y97705D01*
X105347Y97642D01*
X105242Y97621D01*
X105129Y97607D01*
X105080Y98233D01*
X105087D01*
X105101D01*
X105122Y98240D01*
X105157Y98247D01*
X105235Y98268D01*
X105340Y98296D01*
X105446Y98338D01*
X105565Y98395D01*
X105671Y98465D01*
X105770Y98550D01*
X105777Y98564D01*
X105805Y98592D01*
X105840Y98648D01*
X105882Y98726D01*
X105924Y98810D01*
X105960Y98915D01*
X105988Y99035D01*
X105995Y99169D01*
Y99211D01*
X105988Y99239D01*
X105981Y99324D01*
X105952Y99422D01*
X105917Y99542D01*
X105861Y99661D01*
X105777Y99788D01*
X105727Y99844D01*
X105671Y99900D01*
X105664Y99908D01*
X105657Y99915D01*
X105636Y99929D01*
X105615Y99950D01*
X105537Y99999D01*
X105439Y100055D01*
X105319Y100105D01*
X105171Y100154D01*
X104995Y100189D01*
X104904Y100203D01*
X104806D01*
X104798D01*
X104784D01*
X104756D01*
X104721Y100196D01*
X104679D01*
X104630Y100189D01*
X104517Y100168D01*
X104383Y100133D01*
X104250Y100083D01*
X104123Y100013D01*
X104003Y99915D01*
X103996D01*
X103989Y99900D01*
X103954Y99865D01*
X103905Y99802D01*
X103849Y99718D01*
X103799Y99605D01*
X103750Y99478D01*
X103715Y99331D01*
X103701Y99246D01*
Y99112D01*
X103708Y99056D01*
X103715Y98986D01*
X103736Y98901D01*
X103757Y98817D01*
X103792Y98726D01*
X103835Y98634D01*
X103842Y98627D01*
X103856Y98599D01*
X103891Y98557D01*
X103926Y98500D01*
X103975Y98444D01*
X104039Y98388D01*
X104102Y98324D01*
X104179Y98275D01*
X104102Y97712D01*
X101597Y98184D01*
Y100604D01*
X102167D01*
Y98655D01*
X103483Y98395D01*
X103476Y98402D01*
X103469Y98416D01*
X103455Y98437D01*
X103434Y98472D01*
X103413Y98514D01*
X103384Y98564D01*
X103328Y98676D01*
X103272Y98817D01*
X103223Y98972D01*
X103187Y99141D01*
X103173Y99225D01*
Y99380D01*
X103180Y99422D01*
X103187Y99478D01*
X103194Y99542D01*
X103209Y99612D01*
X103230Y99689D01*
X103279Y99858D01*
X103314Y99950D01*
X103363Y100041D01*
X103413Y100133D01*
X103469Y100224D01*
X103539Y100309D01*
X103617Y100393D01*
X103624Y100400D01*
X103638Y100414D01*
X103659Y100435D01*
X103694Y100463D01*
X103743Y100499D01*
X103792Y100534D01*
X103856Y100576D01*
X103926Y100618D01*
X104003Y100653D01*
X104088Y100695D01*
X104186Y100731D01*
X104285Y100766D01*
X104390Y100794D01*
X104510Y100815D01*
X104630Y100829D01*
X104756Y100836D01*
X104763D01*
X104784D01*
X104820D01*
X104869Y100829D01*
D02*
G37*
G36*
X106403Y95475D02*
X102596D01*
X102603Y95468D01*
X102632Y95433D01*
X102674Y95391D01*
X102723Y95320D01*
X102786Y95243D01*
X102857Y95144D01*
X102934Y95032D01*
X103012Y94905D01*
Y94898D01*
X103019Y94891D01*
X103047Y94849D01*
X103082Y94778D01*
X103124Y94694D01*
X103173Y94595D01*
X103223Y94490D01*
X103272Y94384D01*
X103314Y94279D01*
X102737D01*
Y94286D01*
X102723Y94300D01*
X102716Y94328D01*
X102695Y94363D01*
X102674Y94405D01*
X102646Y94455D01*
X102575Y94574D01*
X102498Y94715D01*
X102399Y94856D01*
X102287Y95003D01*
X102167Y95151D01*
X102160Y95158D01*
X102153Y95165D01*
X102132Y95186D01*
X102111Y95215D01*
X102041Y95278D01*
X101956Y95362D01*
X101858Y95447D01*
X101745Y95538D01*
X101632Y95616D01*
X101513Y95686D01*
Y96073D01*
X106403D01*
Y95475D01*
D02*
G37*
G36*
Y92640D02*
X105390Y91999D01*
X105382D01*
X105368Y91985D01*
X105347Y91971D01*
X105319Y91950D01*
X105242Y91901D01*
X105143Y91837D01*
X105038Y91760D01*
X104925Y91683D01*
X104820Y91605D01*
X104721Y91535D01*
X104714Y91528D01*
X104686Y91507D01*
X104644Y91472D01*
X104594Y91422D01*
X104489Y91317D01*
X104440Y91260D01*
X104397Y91204D01*
X104390Y91197D01*
X104383Y91183D01*
X104369Y91155D01*
X104348Y91113D01*
X104327Y91070D01*
X104306Y91021D01*
X104271Y90909D01*
Y90902D01*
X104264Y90888D01*
Y90859D01*
X104257Y90824D01*
X104250Y90775D01*
Y90719D01*
X104243Y90641D01*
Y89811D01*
X106403D01*
Y89164D01*
X101534D01*
Y91422D01*
X101541Y91479D01*
Y91542D01*
X101548Y91690D01*
X101569Y91844D01*
X101590Y92013D01*
X101625Y92168D01*
X101646Y92246D01*
X101668Y92309D01*
Y92316D01*
X101675Y92323D01*
X101696Y92365D01*
X101724Y92428D01*
X101773Y92506D01*
X101837Y92590D01*
X101921Y92682D01*
X102019Y92766D01*
X102132Y92851D01*
X102139D01*
X102146Y92858D01*
X102188Y92886D01*
X102259Y92914D01*
X102350Y92956D01*
X102456Y92991D01*
X102582Y93027D01*
X102716Y93048D01*
X102864Y93055D01*
X102871D01*
X102885D01*
X102913D01*
X102948Y93048D01*
X102997D01*
X103047Y93041D01*
X103166Y93012D01*
X103307Y92970D01*
X103455Y92914D01*
X103603Y92830D01*
X103673Y92773D01*
X103743Y92717D01*
X103750Y92710D01*
X103757Y92703D01*
X103778Y92682D01*
X103799Y92654D01*
X103828Y92618D01*
X103856Y92576D01*
X103891Y92520D01*
X103933Y92464D01*
X103968Y92393D01*
X104003Y92316D01*
X104046Y92231D01*
X104081Y92140D01*
X104109Y92034D01*
X104144Y91929D01*
X104165Y91809D01*
X104186Y91683D01*
X104193Y91697D01*
X104207Y91725D01*
X104236Y91767D01*
X104264Y91823D01*
X104341Y91950D01*
X104390Y92013D01*
X104433Y92070D01*
X104447Y92084D01*
X104482Y92119D01*
X104538Y92175D01*
X104609Y92246D01*
X104707Y92323D01*
X104813Y92414D01*
X104939Y92506D01*
X105080Y92604D01*
X106403Y93442D01*
Y92640D01*
D02*
G37*
G36*
X121277Y99147D02*
X122445D01*
Y98549D01*
X121277D01*
Y96431D01*
X120728D01*
X117576Y98661D01*
Y99147D01*
X120728D01*
Y99808D01*
X121277D01*
Y99147D01*
D02*
G37*
G36*
X122445Y94503D02*
X118638D01*
X118646Y94496D01*
X118674Y94461D01*
X118716Y94419D01*
X118765Y94348D01*
X118828Y94271D01*
X118899Y94172D01*
X118976Y94060D01*
X119054Y93933D01*
Y93926D01*
X119061Y93919D01*
X119089Y93877D01*
X119124Y93806D01*
X119166Y93722D01*
X119215Y93624D01*
X119265Y93518D01*
X119314Y93413D01*
X119356Y93307D01*
X118779D01*
Y93314D01*
X118765Y93328D01*
X118758Y93356D01*
X118737Y93391D01*
X118716Y93434D01*
X118688Y93483D01*
X118617Y93603D01*
X118540Y93743D01*
X118441Y93884D01*
X118329Y94032D01*
X118209Y94179D01*
X118202Y94186D01*
X118195Y94193D01*
X118174Y94215D01*
X118153Y94243D01*
X118083Y94306D01*
X117998Y94390D01*
X117900Y94475D01*
X117787Y94566D01*
X117675Y94644D01*
X117555Y94714D01*
Y95101D01*
X122445D01*
Y94503D01*
D02*
G37*
G36*
Y91668D02*
X121432Y91027D01*
X121425D01*
X121411Y91013D01*
X121390Y90999D01*
X121361Y90978D01*
X121284Y90929D01*
X121186Y90866D01*
X121080Y90788D01*
X120967Y90711D01*
X120862Y90633D01*
X120763Y90563D01*
X120756Y90556D01*
X120728Y90535D01*
X120686Y90500D01*
X120637Y90450D01*
X120531Y90345D01*
X120482Y90289D01*
X120440Y90232D01*
X120433Y90225D01*
X120426Y90211D01*
X120412Y90183D01*
X120391Y90141D01*
X120369Y90099D01*
X120348Y90049D01*
X120313Y89937D01*
Y89930D01*
X120306Y89916D01*
Y89888D01*
X120299Y89852D01*
X120292Y89803D01*
Y89747D01*
X120285Y89670D01*
Y88839D01*
X122445D01*
Y88192D01*
X117576D01*
Y90450D01*
X117583Y90507D01*
Y90570D01*
X117590Y90718D01*
X117611Y90873D01*
X117632Y91041D01*
X117668Y91196D01*
X117689Y91274D01*
X117710Y91337D01*
Y91344D01*
X117717Y91351D01*
X117738Y91393D01*
X117766Y91457D01*
X117815Y91534D01*
X117879Y91618D01*
X117963Y91710D01*
X118062Y91794D01*
X118174Y91879D01*
X118181D01*
X118188Y91886D01*
X118230Y91914D01*
X118301Y91942D01*
X118392Y91984D01*
X118498Y92019D01*
X118624Y92055D01*
X118758Y92076D01*
X118906Y92083D01*
X118913D01*
X118927D01*
X118955D01*
X118990Y92076D01*
X119040D01*
X119089Y92069D01*
X119208Y92041D01*
X119349Y91998D01*
X119497Y91942D01*
X119645Y91858D01*
X119715Y91801D01*
X119785Y91745D01*
X119792Y91738D01*
X119799Y91731D01*
X119821Y91710D01*
X119842Y91682D01*
X119870Y91646D01*
X119898Y91604D01*
X119933Y91548D01*
X119975Y91492D01*
X120010Y91421D01*
X120046Y91344D01*
X120088Y91260D01*
X120123Y91168D01*
X120151Y91063D01*
X120186Y90957D01*
X120208Y90837D01*
X120229Y90711D01*
X120236Y90725D01*
X120250Y90753D01*
X120278Y90795D01*
X120306Y90851D01*
X120383Y90978D01*
X120433Y91041D01*
X120475Y91098D01*
X120489Y91112D01*
X120524Y91147D01*
X120580Y91203D01*
X120651Y91274D01*
X120749Y91351D01*
X120855Y91442D01*
X120982Y91534D01*
X121122Y91632D01*
X122445Y92470D01*
Y91668D01*
D02*
G37*
G36*
X91073Y80812D02*
X91129Y80805D01*
X91193Y80791D01*
X91263Y80776D01*
X91340Y80762D01*
X91509Y80706D01*
X91601Y80664D01*
X91685Y80622D01*
X91777Y80565D01*
X91868Y80502D01*
X91959Y80432D01*
X92044Y80347D01*
X92051Y80340D01*
X92065Y80326D01*
X92086Y80298D01*
X92114Y80263D01*
X92149Y80221D01*
X92185Y80164D01*
X92227Y80101D01*
X92262Y80024D01*
X92304Y79946D01*
X92346Y79855D01*
X92382Y79763D01*
X92417Y79658D01*
X92445Y79545D01*
X92466Y79426D01*
X92480Y79306D01*
X92487Y79172D01*
Y79109D01*
X92480Y79067D01*
X92473Y79010D01*
X92466Y78947D01*
X92452Y78877D01*
X92438Y78799D01*
X92396Y78630D01*
X92325Y78455D01*
X92283Y78363D01*
X92234Y78279D01*
X92170Y78194D01*
X92107Y78110D01*
X92100Y78103D01*
X92086Y78089D01*
X92065Y78068D01*
X92037Y78046D01*
X92002Y78011D01*
X91952Y77976D01*
X91903Y77934D01*
X91840Y77892D01*
X91770Y77849D01*
X91699Y77807D01*
X91530Y77730D01*
X91333Y77667D01*
X91228Y77646D01*
X91115Y77631D01*
X91038Y78229D01*
X91045D01*
X91059Y78236D01*
X91087Y78243D01*
X91122Y78250D01*
X91164Y78258D01*
X91214Y78272D01*
X91319Y78307D01*
X91446Y78356D01*
X91566Y78419D01*
X91678Y78490D01*
X91777Y78574D01*
X91784Y78588D01*
X91812Y78616D01*
X91847Y78673D01*
X91882Y78743D01*
X91924Y78828D01*
X91959Y78933D01*
X91988Y79053D01*
X91995Y79179D01*
Y79222D01*
X91988Y79250D01*
X91981Y79327D01*
X91959Y79426D01*
X91924Y79538D01*
X91875Y79658D01*
X91805Y79777D01*
X91706Y79890D01*
X91692Y79904D01*
X91650Y79939D01*
X91587Y79981D01*
X91502Y80038D01*
X91397Y80094D01*
X91277Y80136D01*
X91136Y80171D01*
X90982Y80185D01*
X90974D01*
X90960D01*
X90939D01*
X90911Y80178D01*
X90834Y80171D01*
X90742Y80150D01*
X90630Y80122D01*
X90517Y80073D01*
X90405Y80002D01*
X90299Y79911D01*
X90285Y79897D01*
X90257Y79862D01*
X90215Y79805D01*
X90165Y79728D01*
X90116Y79630D01*
X90074Y79510D01*
X90046Y79376D01*
X90032Y79229D01*
Y79165D01*
X90039Y79116D01*
X90046Y79053D01*
X90060Y78982D01*
X90074Y78898D01*
X90095Y78806D01*
X89567Y78877D01*
Y78912D01*
X89574Y78940D01*
Y79032D01*
X89560Y79109D01*
X89546Y79200D01*
X89525Y79306D01*
X89490Y79426D01*
X89441Y79538D01*
X89377Y79658D01*
Y79665D01*
X89370Y79672D01*
X89342Y79707D01*
X89293Y79756D01*
X89230Y79812D01*
X89138Y79869D01*
X89033Y79918D01*
X88913Y79953D01*
X88843Y79967D01*
X88765D01*
X88758D01*
X88751D01*
X88709D01*
X88653Y79953D01*
X88575Y79939D01*
X88491Y79911D01*
X88399Y79876D01*
X88308Y79819D01*
X88223Y79742D01*
X88216Y79735D01*
X88188Y79700D01*
X88153Y79651D01*
X88111Y79587D01*
X88076Y79503D01*
X88041Y79404D01*
X88012Y79292D01*
X88005Y79165D01*
Y79109D01*
X88019Y79046D01*
X88034Y78961D01*
X88062Y78870D01*
X88097Y78778D01*
X88153Y78680D01*
X88223Y78588D01*
X88230Y78581D01*
X88266Y78553D01*
X88315Y78511D01*
X88385Y78462D01*
X88477Y78412D01*
X88589Y78363D01*
X88723Y78321D01*
X88878Y78293D01*
X88772Y77695D01*
X88765D01*
X88744Y77702D01*
X88716Y77709D01*
X88674Y77716D01*
X88624Y77730D01*
X88568Y77751D01*
X88434Y77793D01*
X88280Y77864D01*
X88125Y77948D01*
X87977Y78053D01*
X87844Y78187D01*
X87837Y78194D01*
X87829Y78208D01*
X87815Y78229D01*
X87794Y78258D01*
X87766Y78293D01*
X87738Y78342D01*
X87710Y78391D01*
X87675Y78455D01*
X87618Y78595D01*
X87562Y78757D01*
X87527Y78947D01*
X87513Y79046D01*
Y79222D01*
X87520Y79299D01*
X87534Y79390D01*
X87555Y79503D01*
X87590Y79630D01*
X87632Y79756D01*
X87689Y79883D01*
Y79890D01*
X87696Y79897D01*
X87717Y79939D01*
X87759Y80002D01*
X87808Y80073D01*
X87879Y80157D01*
X87956Y80242D01*
X88048Y80326D01*
X88153Y80396D01*
X88167Y80403D01*
X88202Y80425D01*
X88266Y80453D01*
X88343Y80488D01*
X88434Y80523D01*
X88540Y80551D01*
X88660Y80572D01*
X88779Y80579D01*
X88793D01*
X88836D01*
X88892Y80572D01*
X88969Y80558D01*
X89061Y80537D01*
X89159Y80502D01*
X89258Y80460D01*
X89356Y80403D01*
X89370Y80396D01*
X89398Y80375D01*
X89448Y80333D01*
X89504Y80277D01*
X89567Y80206D01*
X89638Y80122D01*
X89701Y80024D01*
X89764Y79904D01*
Y79911D01*
X89771Y79925D01*
X89778Y79946D01*
X89785Y79974D01*
X89813Y80052D01*
X89856Y80150D01*
X89912Y80263D01*
X89982Y80375D01*
X90074Y80481D01*
X90179Y80579D01*
X90194Y80586D01*
X90236Y80615D01*
X90306Y80657D01*
X90398Y80699D01*
X90510Y80741D01*
X90644Y80783D01*
X90799Y80812D01*
X90967Y80819D01*
X90974D01*
X90996D01*
X91031D01*
X91073Y80812D01*
D02*
G37*
G36*
X92403Y75493D02*
X88596D01*
X88603Y75486D01*
X88631Y75450D01*
X88674Y75408D01*
X88723Y75338D01*
X88786Y75260D01*
X88857Y75162D01*
X88934Y75049D01*
X89011Y74923D01*
Y74916D01*
X89018Y74908D01*
X89047Y74866D01*
X89082Y74796D01*
X89124Y74711D01*
X89173Y74613D01*
X89222Y74507D01*
X89272Y74402D01*
X89314Y74296D01*
X88737D01*
Y74303D01*
X88723Y74317D01*
X88716Y74346D01*
X88695Y74381D01*
X88674Y74423D01*
X88646Y74472D01*
X88575Y74592D01*
X88498Y74733D01*
X88399Y74873D01*
X88287Y75021D01*
X88167Y75169D01*
X88160Y75176D01*
X88153Y75183D01*
X88132Y75204D01*
X88111Y75232D01*
X88041Y75296D01*
X87956Y75380D01*
X87858Y75464D01*
X87745Y75556D01*
X87632Y75633D01*
X87513Y75704D01*
Y76091D01*
X92403D01*
Y75493D01*
D02*
G37*
G36*
Y72657D02*
X91390Y72017D01*
X91383D01*
X91368Y72003D01*
X91347Y71989D01*
X91319Y71968D01*
X91242Y71918D01*
X91143Y71855D01*
X91038Y71778D01*
X90925Y71700D01*
X90820Y71623D01*
X90721Y71553D01*
X90714Y71545D01*
X90686Y71524D01*
X90644Y71489D01*
X90595Y71440D01*
X90489Y71334D01*
X90440Y71278D01*
X90398Y71222D01*
X90391Y71215D01*
X90383Y71201D01*
X90369Y71172D01*
X90348Y71130D01*
X90327Y71088D01*
X90306Y71039D01*
X90271Y70926D01*
Y70919D01*
X90264Y70905D01*
Y70877D01*
X90257Y70842D01*
X90250Y70793D01*
Y70736D01*
X90243Y70659D01*
Y69829D01*
X92403D01*
Y69181D01*
X87534D01*
Y71440D01*
X87541Y71496D01*
Y71560D01*
X87548Y71707D01*
X87569Y71862D01*
X87590Y72031D01*
X87625Y72186D01*
X87647Y72263D01*
X87668Y72326D01*
Y72333D01*
X87675Y72340D01*
X87696Y72383D01*
X87724Y72446D01*
X87773Y72523D01*
X87837Y72608D01*
X87921Y72699D01*
X88019Y72784D01*
X88132Y72868D01*
X88139D01*
X88146Y72875D01*
X88188Y72903D01*
X88259Y72931D01*
X88350Y72974D01*
X88456Y73009D01*
X88582Y73044D01*
X88716Y73065D01*
X88864Y73072D01*
X88871D01*
X88885D01*
X88913D01*
X88948Y73065D01*
X88997D01*
X89047Y73058D01*
X89166Y73030D01*
X89307Y72988D01*
X89455Y72931D01*
X89602Y72847D01*
X89673Y72791D01*
X89743Y72734D01*
X89750Y72727D01*
X89757Y72720D01*
X89778Y72699D01*
X89799Y72671D01*
X89828Y72636D01*
X89856Y72594D01*
X89891Y72537D01*
X89933Y72481D01*
X89968Y72411D01*
X90003Y72333D01*
X90046Y72249D01*
X90081Y72158D01*
X90109Y72052D01*
X90144Y71947D01*
X90165Y71827D01*
X90186Y71700D01*
X90194Y71714D01*
X90208Y71742D01*
X90236Y71785D01*
X90264Y71841D01*
X90341Y71968D01*
X90391Y72031D01*
X90433Y72087D01*
X90447Y72101D01*
X90482Y72136D01*
X90538Y72193D01*
X90609Y72263D01*
X90707Y72340D01*
X90813Y72432D01*
X90939Y72523D01*
X91080Y72622D01*
X92403Y73459D01*
Y72657D01*
D02*
G37*
G36*
X57445Y83565D02*
X57438D01*
X57410D01*
X57368D01*
X57311Y83572D01*
X57248Y83579D01*
X57178Y83593D01*
X57107Y83607D01*
X57030Y83635D01*
X57023D01*
X57016Y83642D01*
X56974Y83656D01*
X56910Y83684D01*
X56826Y83726D01*
X56727Y83783D01*
X56615Y83853D01*
X56502Y83930D01*
X56382Y84029D01*
X56375D01*
X56368Y84043D01*
X56326Y84078D01*
X56263Y84142D01*
X56171Y84233D01*
X56066Y84339D01*
X55939Y84472D01*
X55799Y84634D01*
X55651Y84810D01*
X55644Y84817D01*
X55623Y84845D01*
X55588Y84887D01*
X55545Y84937D01*
X55489Y85000D01*
X55426Y85077D01*
X55355Y85155D01*
X55278Y85246D01*
X55109Y85422D01*
X54940Y85598D01*
X54856Y85682D01*
X54771Y85760D01*
X54694Y85830D01*
X54616Y85886D01*
X54609D01*
X54602Y85900D01*
X54581Y85914D01*
X54553Y85929D01*
X54476Y85978D01*
X54384Y86034D01*
X54272Y86083D01*
X54152Y86133D01*
X54019Y86161D01*
X53892Y86175D01*
X53885D01*
X53878D01*
X53836Y86168D01*
X53765Y86161D01*
X53688Y86140D01*
X53589Y86111D01*
X53491Y86062D01*
X53392Y85999D01*
X53294Y85914D01*
X53280Y85900D01*
X53252Y85865D01*
X53216Y85816D01*
X53167Y85739D01*
X53125Y85640D01*
X53083Y85527D01*
X53055Y85394D01*
X53047Y85246D01*
Y85204D01*
X53055Y85176D01*
X53062Y85091D01*
X53083Y84993D01*
X53111Y84887D01*
X53160Y84768D01*
X53223Y84655D01*
X53308Y84550D01*
X53322Y84536D01*
X53357Y84507D01*
X53413Y84465D01*
X53498Y84423D01*
X53596Y84374D01*
X53723Y84332D01*
X53864Y84303D01*
X54026Y84289D01*
X53962Y83677D01*
X53955D01*
X53934Y83684D01*
X53899D01*
X53850Y83691D01*
X53793Y83705D01*
X53730Y83719D01*
X53653Y83740D01*
X53575Y83762D01*
X53406Y83818D01*
X53238Y83902D01*
X53153Y83952D01*
X53069Y84015D01*
X52991Y84078D01*
X52921Y84149D01*
X52914Y84156D01*
X52907Y84170D01*
X52886Y84191D01*
X52865Y84226D01*
X52836Y84268D01*
X52808Y84317D01*
X52773Y84374D01*
X52738Y84444D01*
X52703Y84521D01*
X52668Y84606D01*
X52639Y84697D01*
X52611Y84796D01*
X52590Y84901D01*
X52569Y85014D01*
X52562Y85133D01*
X52555Y85260D01*
Y85330D01*
X52562Y85380D01*
X52569Y85436D01*
X52576Y85506D01*
X52590Y85584D01*
X52604Y85661D01*
X52653Y85844D01*
X52724Y86027D01*
X52766Y86118D01*
X52815Y86210D01*
X52879Y86294D01*
X52949Y86372D01*
X52956Y86379D01*
X52963Y86393D01*
X52991Y86407D01*
X53019Y86435D01*
X53055Y86470D01*
X53104Y86505D01*
X53153Y86541D01*
X53216Y86583D01*
X53350Y86653D01*
X53519Y86724D01*
X53603Y86752D01*
X53702Y86766D01*
X53800Y86780D01*
X53906Y86787D01*
X53920D01*
X53955D01*
X54011Y86780D01*
X54089Y86773D01*
X54173Y86759D01*
X54272Y86731D01*
X54377Y86702D01*
X54483Y86660D01*
X54497Y86653D01*
X54532Y86639D01*
X54588Y86611D01*
X54666Y86569D01*
X54750Y86513D01*
X54856Y86442D01*
X54961Y86358D01*
X55081Y86259D01*
X55095Y86245D01*
X55137Y86210D01*
X55172Y86175D01*
X55208Y86140D01*
X55250Y86097D01*
X55306Y86041D01*
X55362Y85985D01*
X55426Y85914D01*
X55496Y85844D01*
X55573Y85760D01*
X55651Y85668D01*
X55742Y85570D01*
X55834Y85457D01*
X55932Y85345D01*
X55939Y85338D01*
X55953Y85323D01*
X55974Y85295D01*
X56003Y85260D01*
X56045Y85218D01*
X56087Y85169D01*
X56178Y85056D01*
X56284Y84937D01*
X56389Y84824D01*
X56481Y84726D01*
X56516Y84683D01*
X56551Y84648D01*
X56558Y84641D01*
X56579Y84620D01*
X56608Y84592D01*
X56650Y84557D01*
X56699Y84521D01*
X56748Y84479D01*
X56868Y84395D01*
Y86794D01*
X57445D01*
Y83565D01*
D02*
G37*
G36*
Y81517D02*
X53639D01*
X53646Y81510D01*
X53674Y81475D01*
X53716Y81433D01*
X53765Y81362D01*
X53829Y81285D01*
X53899Y81187D01*
X53976Y81074D01*
X54054Y80947D01*
Y80940D01*
X54061Y80933D01*
X54089Y80891D01*
X54124Y80821D01*
X54166Y80736D01*
X54215Y80638D01*
X54265Y80532D01*
X54314Y80427D01*
X54356Y80321D01*
X53779D01*
Y80328D01*
X53765Y80342D01*
X53758Y80370D01*
X53737Y80406D01*
X53716Y80448D01*
X53688Y80497D01*
X53617Y80617D01*
X53540Y80757D01*
X53442Y80898D01*
X53329Y81046D01*
X53209Y81194D01*
X53202Y81201D01*
X53195Y81208D01*
X53174Y81229D01*
X53153Y81257D01*
X53083Y81320D01*
X52998Y81405D01*
X52900Y81489D01*
X52787Y81580D01*
X52675Y81658D01*
X52555Y81728D01*
Y82115D01*
X57445D01*
Y81517D01*
D02*
G37*
G36*
Y78682D02*
X56432Y78041D01*
X56425D01*
X56411Y78027D01*
X56389Y78013D01*
X56361Y77992D01*
X56284Y77943D01*
X56185Y77880D01*
X56080Y77802D01*
X55967Y77725D01*
X55862Y77647D01*
X55763Y77577D01*
X55756Y77570D01*
X55728Y77549D01*
X55686Y77514D01*
X55637Y77464D01*
X55531Y77359D01*
X55482Y77303D01*
X55440Y77246D01*
X55433Y77239D01*
X55426Y77225D01*
X55412Y77197D01*
X55391Y77155D01*
X55369Y77113D01*
X55348Y77063D01*
X55313Y76951D01*
Y76944D01*
X55306Y76930D01*
Y76902D01*
X55299Y76866D01*
X55292Y76817D01*
Y76761D01*
X55285Y76684D01*
Y75853D01*
X57445D01*
Y75206D01*
X52576D01*
Y77464D01*
X52583Y77521D01*
Y77584D01*
X52590Y77732D01*
X52611Y77887D01*
X52632Y78056D01*
X52668Y78210D01*
X52689Y78288D01*
X52710Y78351D01*
Y78358D01*
X52717Y78365D01*
X52738Y78407D01*
X52766Y78471D01*
X52815Y78548D01*
X52879Y78632D01*
X52963Y78724D01*
X53062Y78808D01*
X53174Y78893D01*
X53181D01*
X53188Y78900D01*
X53231Y78928D01*
X53301Y78956D01*
X53392Y78998D01*
X53498Y79033D01*
X53625Y79069D01*
X53758Y79090D01*
X53906Y79097D01*
X53913D01*
X53927D01*
X53955D01*
X53990Y79090D01*
X54040D01*
X54089Y79083D01*
X54208Y79055D01*
X54349Y79012D01*
X54497Y78956D01*
X54645Y78872D01*
X54715Y78815D01*
X54785Y78759D01*
X54792Y78752D01*
X54799Y78745D01*
X54821Y78724D01*
X54842Y78696D01*
X54870Y78661D01*
X54898Y78618D01*
X54933Y78562D01*
X54975Y78506D01*
X55010Y78436D01*
X55046Y78358D01*
X55088Y78274D01*
X55123Y78182D01*
X55151Y78077D01*
X55186Y77971D01*
X55208Y77852D01*
X55229Y77725D01*
X55236Y77739D01*
X55250Y77767D01*
X55278Y77809D01*
X55306Y77866D01*
X55383Y77992D01*
X55433Y78056D01*
X55475Y78112D01*
X55489Y78126D01*
X55524Y78161D01*
X55580Y78217D01*
X55651Y78288D01*
X55749Y78365D01*
X55855Y78457D01*
X55981Y78548D01*
X56122Y78646D01*
X57445Y79484D01*
Y78682D01*
D02*
G37*
G36*
X79847Y382514D02*
X79249D01*
Y386320D01*
X79242Y386313D01*
X79207Y386285D01*
X79165Y386242D01*
X79094Y386193D01*
X79017Y386130D01*
X78918Y386060D01*
X78806Y385982D01*
X78679Y385905D01*
X78672D01*
X78665Y385898D01*
X78623Y385870D01*
X78553Y385834D01*
X78468Y385792D01*
X78370Y385743D01*
X78264Y385694D01*
X78159Y385644D01*
X78053Y385602D01*
Y386179D01*
X78060D01*
X78074Y386193D01*
X78102Y386200D01*
X78137Y386221D01*
X78180Y386242D01*
X78229Y386271D01*
X78349Y386341D01*
X78489Y386418D01*
X78630Y386517D01*
X78778Y386629D01*
X78925Y386749D01*
X78933Y386756D01*
X78940Y386763D01*
X78961Y386784D01*
X78989Y386805D01*
X79052Y386876D01*
X79137Y386960D01*
X79221Y387059D01*
X79313Y387171D01*
X79390Y387284D01*
X79460Y387403D01*
X79847D01*
Y382514D01*
D02*
G37*
G36*
X76062D02*
X75464D01*
Y386320D01*
X75457Y386313D01*
X75422Y386285D01*
X75380Y386242D01*
X75309Y386193D01*
X75232Y386130D01*
X75133Y386060D01*
X75021Y385982D01*
X74894Y385905D01*
X74887D01*
X74880Y385898D01*
X74838Y385870D01*
X74767Y385834D01*
X74683Y385792D01*
X74584Y385743D01*
X74479Y385694D01*
X74373Y385644D01*
X74268Y385602D01*
Y386179D01*
X74275D01*
X74289Y386193D01*
X74317Y386200D01*
X74352Y386221D01*
X74394Y386242D01*
X74444Y386271D01*
X74563Y386341D01*
X74704Y386418D01*
X74845Y386517D01*
X74992Y386629D01*
X75140Y386749D01*
X75147Y386756D01*
X75154Y386763D01*
X75175Y386784D01*
X75204Y386805D01*
X75267Y386876D01*
X75351Y386960D01*
X75436Y387059D01*
X75527Y387171D01*
X75605Y387284D01*
X75675Y387403D01*
X76062D01*
Y382514D01*
D02*
G37*
G36*
X71468Y387375D02*
X71531D01*
X71679Y387368D01*
X71833Y387347D01*
X72002Y387326D01*
X72157Y387291D01*
X72235Y387270D01*
X72298Y387249D01*
X72305D01*
X72312Y387242D01*
X72354Y387220D01*
X72417Y387192D01*
X72495Y387143D01*
X72579Y387080D01*
X72671Y386995D01*
X72755Y386897D01*
X72840Y386784D01*
Y386777D01*
X72847Y386770D01*
X72875Y386728D01*
X72903Y386658D01*
X72945Y386566D01*
X72980Y386461D01*
X73015Y386334D01*
X73037Y386200D01*
X73044Y386053D01*
Y386045D01*
Y386031D01*
Y386003D01*
X73037Y385968D01*
Y385919D01*
X73029Y385870D01*
X73001Y385750D01*
X72959Y385609D01*
X72903Y385462D01*
X72818Y385314D01*
X72762Y385243D01*
X72706Y385173D01*
X72699Y385166D01*
X72692Y385159D01*
X72671Y385138D01*
X72643Y385117D01*
X72607Y385089D01*
X72565Y385061D01*
X72509Y385025D01*
X72453Y384983D01*
X72382Y384948D01*
X72305Y384913D01*
X72220Y384870D01*
X72129Y384835D01*
X72023Y384807D01*
X71918Y384772D01*
X71798Y384751D01*
X71672Y384730D01*
X71686Y384723D01*
X71714Y384709D01*
X71756Y384680D01*
X71812Y384652D01*
X71939Y384575D01*
X72002Y384526D01*
X72059Y384483D01*
X72073Y384469D01*
X72108Y384434D01*
X72164Y384378D01*
X72235Y384308D01*
X72312Y384209D01*
X72403Y384104D01*
X72495Y383977D01*
X72593Y383836D01*
X73431Y382514D01*
X72628D01*
X71988Y383527D01*
Y383534D01*
X71974Y383548D01*
X71960Y383569D01*
X71939Y383597D01*
X71890Y383674D01*
X71826Y383773D01*
X71749Y383879D01*
X71672Y383991D01*
X71594Y384097D01*
X71524Y384195D01*
X71517Y384202D01*
X71496Y384230D01*
X71460Y384272D01*
X71411Y384322D01*
X71306Y384427D01*
X71249Y384477D01*
X71193Y384519D01*
X71186Y384526D01*
X71172Y384533D01*
X71144Y384547D01*
X71102Y384568D01*
X71059Y384589D01*
X71010Y384610D01*
X70898Y384645D01*
X70891D01*
X70877Y384652D01*
X70848D01*
X70813Y384659D01*
X70764Y384666D01*
X70708D01*
X70630Y384674D01*
X69800D01*
Y382514D01*
X69153D01*
Y387382D01*
X71411D01*
X71468Y387375D01*
D02*
G37*
G36*
X60487Y114438D02*
X60543Y114431D01*
X60614Y114424D01*
X60691Y114410D01*
X60769Y114396D01*
X60951Y114347D01*
X61135Y114276D01*
X61226Y114234D01*
X61317Y114185D01*
X61402Y114121D01*
X61479Y114051D01*
X61486Y114044D01*
X61500Y114037D01*
X61514Y114009D01*
X61543Y113981D01*
X61578Y113945D01*
X61613Y113896D01*
X61648Y113847D01*
X61690Y113784D01*
X61761Y113650D01*
X61831Y113481D01*
X61859Y113397D01*
X61873Y113298D01*
X61887Y113200D01*
X61894Y113094D01*
Y113080D01*
Y113045D01*
X61887Y112989D01*
X61880Y112911D01*
X61866Y112827D01*
X61838Y112728D01*
X61810Y112623D01*
X61768Y112517D01*
X61761Y112503D01*
X61747Y112468D01*
X61718Y112412D01*
X61676Y112334D01*
X61620Y112250D01*
X61550Y112144D01*
X61465Y112039D01*
X61367Y111919D01*
X61353Y111905D01*
X61317Y111863D01*
X61282Y111828D01*
X61247Y111792D01*
X61205Y111750D01*
X61149Y111694D01*
X61092Y111638D01*
X61022Y111574D01*
X60951Y111504D01*
X60867Y111427D01*
X60776Y111349D01*
X60677Y111258D01*
X60565Y111166D01*
X60452Y111068D01*
X60445Y111061D01*
X60431Y111047D01*
X60403Y111026D01*
X60368Y110997D01*
X60325Y110955D01*
X60276Y110913D01*
X60163Y110822D01*
X60044Y110716D01*
X59931Y110610D01*
X59833Y110519D01*
X59791Y110484D01*
X59756Y110449D01*
X59748Y110442D01*
X59727Y110421D01*
X59699Y110392D01*
X59664Y110350D01*
X59629Y110301D01*
X59587Y110252D01*
X59502Y110132D01*
X61901D01*
Y109555D01*
X58672D01*
Y109562D01*
Y109590D01*
Y109633D01*
X58679Y109689D01*
X58686Y109752D01*
X58700Y109822D01*
X58714Y109893D01*
X58742Y109970D01*
Y109977D01*
X58749Y109984D01*
X58763Y110027D01*
X58792Y110090D01*
X58834Y110174D01*
X58890Y110273D01*
X58960Y110385D01*
X59038Y110498D01*
X59136Y110618D01*
Y110625D01*
X59150Y110632D01*
X59186Y110674D01*
X59249Y110737D01*
X59340Y110829D01*
X59446Y110934D01*
X59580Y111061D01*
X59741Y111201D01*
X59917Y111349D01*
X59924Y111356D01*
X59953Y111377D01*
X59995Y111412D01*
X60044Y111455D01*
X60107Y111511D01*
X60185Y111574D01*
X60262Y111645D01*
X60353Y111722D01*
X60529Y111891D01*
X60705Y112060D01*
X60790Y112144D01*
X60867Y112229D01*
X60938Y112306D01*
X60994Y112383D01*
Y112390D01*
X61008Y112397D01*
X61022Y112419D01*
X61036Y112447D01*
X61085Y112524D01*
X61142Y112616D01*
X61191Y112728D01*
X61240Y112848D01*
X61268Y112982D01*
X61282Y113108D01*
Y113115D01*
Y113122D01*
X61275Y113164D01*
X61268Y113235D01*
X61247Y113312D01*
X61219Y113411D01*
X61170Y113509D01*
X61106Y113608D01*
X61022Y113706D01*
X61008Y113720D01*
X60973Y113748D01*
X60923Y113784D01*
X60846Y113833D01*
X60747Y113875D01*
X60635Y113917D01*
X60501Y113945D01*
X60353Y113953D01*
X60311D01*
X60283Y113945D01*
X60199Y113938D01*
X60100Y113917D01*
X59995Y113889D01*
X59875Y113840D01*
X59763Y113777D01*
X59657Y113692D01*
X59643Y113678D01*
X59615Y113643D01*
X59573Y113587D01*
X59530Y113502D01*
X59481Y113404D01*
X59439Y113277D01*
X59411Y113136D01*
X59397Y112975D01*
X58784Y113038D01*
Y113045D01*
X58792Y113066D01*
Y113101D01*
X58799Y113150D01*
X58813Y113207D01*
X58827Y113270D01*
X58848Y113347D01*
X58869Y113425D01*
X58925Y113594D01*
X59010Y113763D01*
X59059Y113847D01*
X59122Y113931D01*
X59186Y114009D01*
X59256Y114079D01*
X59263Y114086D01*
X59277Y114093D01*
X59298Y114114D01*
X59333Y114135D01*
X59376Y114164D01*
X59425Y114192D01*
X59481Y114227D01*
X59551Y114262D01*
X59629Y114297D01*
X59713Y114332D01*
X59805Y114361D01*
X59903Y114389D01*
X60009Y114410D01*
X60121Y114431D01*
X60241Y114438D01*
X60368Y114445D01*
X60438D01*
X60487Y114438D01*
D02*
G37*
G36*
X56413Y114417D02*
X56477D01*
X56624Y114410D01*
X56779Y114389D01*
X56948Y114368D01*
X57103Y114332D01*
X57180Y114311D01*
X57244Y114290D01*
X57251D01*
X57258Y114283D01*
X57300Y114262D01*
X57363Y114234D01*
X57441Y114185D01*
X57525Y114121D01*
X57617Y114037D01*
X57701Y113938D01*
X57785Y113826D01*
Y113819D01*
X57793Y113812D01*
X57821Y113770D01*
X57849Y113699D01*
X57891Y113608D01*
X57926Y113502D01*
X57961Y113376D01*
X57982Y113242D01*
X57990Y113094D01*
Y113087D01*
Y113073D01*
Y113045D01*
X57982Y113010D01*
Y112960D01*
X57975Y112911D01*
X57947Y112792D01*
X57905Y112651D01*
X57849Y112503D01*
X57764Y112355D01*
X57708Y112285D01*
X57652Y112215D01*
X57645Y112208D01*
X57638Y112200D01*
X57617Y112179D01*
X57588Y112158D01*
X57553Y112130D01*
X57511Y112102D01*
X57455Y112067D01*
X57399Y112025D01*
X57328Y111989D01*
X57251Y111954D01*
X57166Y111912D01*
X57075Y111877D01*
X56969Y111849D01*
X56864Y111814D01*
X56744Y111792D01*
X56617Y111771D01*
X56632Y111764D01*
X56660Y111750D01*
X56702Y111722D01*
X56758Y111694D01*
X56885Y111617D01*
X56948Y111567D01*
X57004Y111525D01*
X57018Y111511D01*
X57054Y111476D01*
X57110Y111420D01*
X57180Y111349D01*
X57258Y111251D01*
X57349Y111145D01*
X57441Y111018D01*
X57539Y110878D01*
X58376Y109555D01*
X57574D01*
X56934Y110568D01*
Y110575D01*
X56920Y110589D01*
X56906Y110610D01*
X56885Y110639D01*
X56836Y110716D01*
X56772Y110815D01*
X56695Y110920D01*
X56617Y111033D01*
X56540Y111138D01*
X56470Y111237D01*
X56463Y111244D01*
X56442Y111272D01*
X56406Y111314D01*
X56357Y111363D01*
X56252Y111469D01*
X56195Y111518D01*
X56139Y111560D01*
X56132Y111567D01*
X56118Y111574D01*
X56090Y111588D01*
X56048Y111609D01*
X56005Y111631D01*
X55956Y111652D01*
X55844Y111687D01*
X55837D01*
X55822Y111694D01*
X55794D01*
X55759Y111701D01*
X55710Y111708D01*
X55654D01*
X55576Y111715D01*
X54746D01*
Y109555D01*
X54099D01*
Y114424D01*
X56357D01*
X56413Y114417D01*
D02*
G37*
G36*
X28389Y85512D02*
X28452Y85505D01*
X28530Y85498D01*
X28607Y85491D01*
X28698Y85470D01*
X28888Y85427D01*
X29099Y85364D01*
X29205Y85322D01*
X29303Y85273D01*
X29402Y85209D01*
X29500Y85146D01*
X29508Y85139D01*
X29522Y85132D01*
X29550Y85111D01*
X29585Y85076D01*
X29620Y85040D01*
X29669Y84991D01*
X29719Y84935D01*
X29775Y84879D01*
X29831Y84808D01*
X29887Y84724D01*
X29951Y84639D01*
X30007Y84548D01*
X30056Y84442D01*
X30113Y84337D01*
X30155Y84224D01*
X30197Y84098D01*
X29564Y83950D01*
Y83957D01*
X29557Y83971D01*
X29543Y83999D01*
X29529Y84034D01*
X29515Y84076D01*
X29493Y84133D01*
X29437Y84245D01*
X29367Y84372D01*
X29282Y84499D01*
X29177Y84618D01*
X29064Y84724D01*
X29050Y84738D01*
X29008Y84766D01*
X28938Y84801D01*
X28846Y84850D01*
X28726Y84893D01*
X28593Y84935D01*
X28431Y84963D01*
X28255Y84970D01*
X28199D01*
X28164Y84963D01*
X28114D01*
X28058Y84956D01*
X27924Y84935D01*
X27777Y84907D01*
X27622Y84858D01*
X27460Y84787D01*
X27312Y84696D01*
X27305D01*
X27298Y84682D01*
X27249Y84646D01*
X27186Y84590D01*
X27108Y84506D01*
X27017Y84400D01*
X26932Y84281D01*
X26855Y84133D01*
X26785Y83971D01*
Y83964D01*
X26778Y83950D01*
X26771Y83929D01*
X26764Y83894D01*
X26749Y83851D01*
X26735Y83802D01*
X26714Y83682D01*
X26686Y83542D01*
X26658Y83387D01*
X26644Y83218D01*
X26637Y83035D01*
Y83028D01*
Y83007D01*
Y82972D01*
Y82930D01*
X26644Y82880D01*
Y82817D01*
X26651Y82747D01*
X26658Y82669D01*
X26679Y82500D01*
X26714Y82317D01*
X26756Y82135D01*
X26813Y81952D01*
Y81945D01*
X26820Y81931D01*
X26834Y81910D01*
X26848Y81874D01*
X26890Y81790D01*
X26953Y81691D01*
X27031Y81579D01*
X27129Y81459D01*
X27242Y81354D01*
X27376Y81255D01*
X27383D01*
X27397Y81248D01*
X27418Y81234D01*
X27446Y81220D01*
X27481Y81206D01*
X27523Y81185D01*
X27622Y81143D01*
X27748Y81100D01*
X27889Y81065D01*
X28044Y81037D01*
X28206Y81030D01*
X28255D01*
X28297Y81037D01*
X28347D01*
X28396Y81044D01*
X28523Y81072D01*
X28670Y81107D01*
X28818Y81164D01*
X28973Y81241D01*
X29050Y81283D01*
X29121Y81340D01*
X29128Y81347D01*
X29135Y81354D01*
X29156Y81375D01*
X29184Y81396D01*
X29212Y81431D01*
X29247Y81473D01*
X29289Y81516D01*
X29325Y81572D01*
X29367Y81635D01*
X29416Y81705D01*
X29458Y81776D01*
X29500Y81860D01*
X29536Y81952D01*
X29571Y82050D01*
X29606Y82156D01*
X29634Y82268D01*
X30281Y82107D01*
Y82099D01*
X30274Y82071D01*
X30260Y82029D01*
X30239Y81973D01*
X30218Y81910D01*
X30190Y81832D01*
X30155Y81748D01*
X30113Y81656D01*
X30014Y81459D01*
X29887Y81262D01*
X29810Y81164D01*
X29733Y81065D01*
X29648Y80981D01*
X29550Y80896D01*
X29543Y80889D01*
X29529Y80875D01*
X29493Y80861D01*
X29458Y80833D01*
X29402Y80798D01*
X29346Y80763D01*
X29268Y80727D01*
X29191Y80692D01*
X29099Y80650D01*
X29001Y80615D01*
X28895Y80580D01*
X28783Y80545D01*
X28663Y80516D01*
X28537Y80502D01*
X28403Y80488D01*
X28262Y80481D01*
X28185D01*
X28128Y80488D01*
X28065D01*
X27988Y80495D01*
X27903Y80509D01*
X27805Y80523D01*
X27601Y80559D01*
X27390Y80615D01*
X27179Y80692D01*
X27080Y80742D01*
X26982Y80798D01*
X26975Y80805D01*
X26960Y80812D01*
X26932Y80833D01*
X26904Y80861D01*
X26862Y80889D01*
X26813Y80932D01*
X26756Y80981D01*
X26700Y81037D01*
X26644Y81100D01*
X26581Y81164D01*
X26454Y81326D01*
X26334Y81516D01*
X26229Y81727D01*
Y81734D01*
X26215Y81755D01*
X26208Y81790D01*
X26187Y81832D01*
X26172Y81888D01*
X26151Y81959D01*
X26123Y82036D01*
X26102Y82121D01*
X26081Y82212D01*
X26053Y82317D01*
X26018Y82536D01*
X25990Y82782D01*
X25975Y83035D01*
Y83042D01*
Y83070D01*
Y83113D01*
X25982Y83162D01*
Y83232D01*
X25990Y83303D01*
X25997Y83394D01*
X26011Y83485D01*
X26046Y83689D01*
X26095Y83915D01*
X26165Y84140D01*
X26264Y84358D01*
X26271Y84365D01*
X26278Y84386D01*
X26292Y84414D01*
X26320Y84449D01*
X26348Y84499D01*
X26384Y84555D01*
X26475Y84682D01*
X26595Y84822D01*
X26735Y84963D01*
X26897Y85104D01*
X27087Y85223D01*
X27094Y85230D01*
X27115Y85237D01*
X27143Y85252D01*
X27179Y85273D01*
X27235Y85294D01*
X27291Y85315D01*
X27362Y85343D01*
X27439Y85371D01*
X27523Y85399D01*
X27615Y85427D01*
X27812Y85470D01*
X28037Y85505D01*
X28269Y85519D01*
X28340D01*
X28389Y85512D01*
D02*
G37*
G36*
X34025Y84900D02*
X34017Y84893D01*
X34003Y84879D01*
X33975Y84850D01*
X33947Y84808D01*
X33905Y84759D01*
X33849Y84703D01*
X33792Y84632D01*
X33729Y84548D01*
X33666Y84464D01*
X33588Y84365D01*
X33511Y84252D01*
X33433Y84140D01*
X33349Y84013D01*
X33265Y83879D01*
X33180Y83732D01*
X33096Y83584D01*
X33089Y83577D01*
X33075Y83549D01*
X33054Y83507D01*
X33018Y83443D01*
X32983Y83366D01*
X32941Y83281D01*
X32892Y83183D01*
X32843Y83070D01*
X32786Y82944D01*
X32723Y82817D01*
X32667Y82676D01*
X32610Y82529D01*
X32498Y82226D01*
X32392Y81902D01*
Y81895D01*
X32385Y81874D01*
X32378Y81839D01*
X32364Y81797D01*
X32350Y81741D01*
X32336Y81670D01*
X32315Y81593D01*
X32301Y81508D01*
X32280Y81410D01*
X32259Y81304D01*
X32223Y81079D01*
X32188Y80833D01*
X32167Y80566D01*
X31555D01*
Y80573D01*
Y80594D01*
Y80622D01*
X31562Y80664D01*
Y80720D01*
X31569Y80791D01*
X31576Y80868D01*
X31583Y80953D01*
X31597Y81051D01*
X31611Y81150D01*
X31632Y81269D01*
X31653Y81389D01*
X31674Y81516D01*
X31703Y81656D01*
X31773Y81945D01*
Y81952D01*
X31780Y81980D01*
X31794Y82022D01*
X31815Y82085D01*
X31836Y82156D01*
X31865Y82240D01*
X31893Y82339D01*
X31935Y82444D01*
X31977Y82564D01*
X32019Y82683D01*
X32125Y82951D01*
X32251Y83232D01*
X32392Y83514D01*
X32399Y83521D01*
X32413Y83549D01*
X32434Y83584D01*
X32462Y83640D01*
X32498Y83704D01*
X32547Y83781D01*
X32596Y83865D01*
X32652Y83957D01*
X32786Y84161D01*
X32927Y84372D01*
X33089Y84590D01*
X33258Y84794D01*
X30872D01*
Y85371D01*
X34025D01*
Y84900D01*
D02*
G37*
G36*
X210653Y91448D02*
X210702D01*
X210758Y91441D01*
X210892Y91413D01*
X211040Y91378D01*
X211194Y91322D01*
X211349Y91237D01*
X211426Y91188D01*
X211497Y91132D01*
X211504Y91125D01*
X211511Y91118D01*
X211532Y91097D01*
X211553Y91076D01*
X211588Y91040D01*
X211616Y90998D01*
X211694Y90900D01*
X211771Y90773D01*
X211842Y90618D01*
X211905Y90442D01*
X211947Y90245D01*
X211349Y90196D01*
Y90203D01*
X211342Y90210D01*
X211335Y90252D01*
X211314Y90316D01*
X211286Y90393D01*
X211258Y90478D01*
X211215Y90562D01*
X211166Y90639D01*
X211117Y90703D01*
X211103Y90717D01*
X211075Y90745D01*
X211025Y90787D01*
X210955Y90836D01*
X210864Y90879D01*
X210765Y90921D01*
X210646Y90949D01*
X210519Y90963D01*
X210470D01*
X210413Y90956D01*
X210350Y90942D01*
X210266Y90921D01*
X210181Y90893D01*
X210097Y90857D01*
X210012Y90801D01*
X209998Y90794D01*
X209963Y90766D01*
X209914Y90717D01*
X209850Y90646D01*
X209780Y90562D01*
X209703Y90463D01*
X209632Y90337D01*
X209562Y90196D01*
Y90189D01*
X209555Y90175D01*
X209548Y90154D01*
X209534Y90126D01*
X209527Y90084D01*
X209513Y90034D01*
X209499Y89978D01*
X209485Y89908D01*
X209463Y89830D01*
X209449Y89746D01*
X209435Y89654D01*
X209428Y89556D01*
X209414Y89443D01*
X209407Y89331D01*
X209400Y89204D01*
Y89077D01*
X209407Y89084D01*
X209435Y89127D01*
X209485Y89183D01*
X209548Y89253D01*
X209618Y89338D01*
X209710Y89415D01*
X209808Y89493D01*
X209921Y89563D01*
X209928D01*
X209935Y89570D01*
X209977Y89591D01*
X210040Y89612D01*
X210125Y89647D01*
X210223Y89675D01*
X210336Y89697D01*
X210455Y89718D01*
X210582Y89725D01*
X210638D01*
X210681Y89718D01*
X210737Y89711D01*
X210793Y89704D01*
X210864Y89690D01*
X210934Y89668D01*
X211096Y89619D01*
X211180Y89584D01*
X211265Y89535D01*
X211349Y89486D01*
X211441Y89429D01*
X211525Y89359D01*
X211602Y89281D01*
X211609Y89274D01*
X211623Y89260D01*
X211644Y89239D01*
X211666Y89204D01*
X211701Y89155D01*
X211736Y89106D01*
X211771Y89042D01*
X211813Y88972D01*
X211856Y88895D01*
X211891Y88810D01*
X211926Y88712D01*
X211961Y88613D01*
X211982Y88507D01*
X212003Y88388D01*
X212017Y88268D01*
X212024Y88142D01*
Y88135D01*
Y88120D01*
Y88099D01*
Y88064D01*
X212017Y88022D01*
Y87980D01*
X211996Y87867D01*
X211975Y87734D01*
X211940Y87593D01*
X211891Y87438D01*
X211820Y87290D01*
Y87283D01*
X211813Y87276D01*
X211799Y87255D01*
X211785Y87227D01*
X211743Y87157D01*
X211680Y87065D01*
X211602Y86967D01*
X211511Y86868D01*
X211398Y86770D01*
X211279Y86685D01*
X211272D01*
X211265Y86678D01*
X211243Y86664D01*
X211215Y86657D01*
X211145Y86622D01*
X211054Y86587D01*
X210934Y86545D01*
X210800Y86516D01*
X210653Y86488D01*
X210491Y86481D01*
X210455D01*
X210420Y86488D01*
X210364D01*
X210301Y86495D01*
X210230Y86509D01*
X210146Y86530D01*
X210061Y86552D01*
X209963Y86580D01*
X209865Y86615D01*
X209766Y86657D01*
X209660Y86713D01*
X209562Y86777D01*
X209463Y86847D01*
X209365Y86931D01*
X209273Y87030D01*
X209266Y87037D01*
X209252Y87058D01*
X209231Y87086D01*
X209203Y87135D01*
X209161Y87199D01*
X209126Y87269D01*
X209083Y87361D01*
X209041Y87459D01*
X208992Y87579D01*
X208950Y87712D01*
X208915Y87860D01*
X208880Y88022D01*
X208844Y88205D01*
X208823Y88402D01*
X208809Y88613D01*
X208802Y88838D01*
Y88845D01*
Y88852D01*
Y88873D01*
Y88902D01*
X208809Y88972D01*
Y89070D01*
X208816Y89183D01*
X208830Y89317D01*
X208844Y89464D01*
X208865Y89626D01*
X208894Y89788D01*
X208929Y89964D01*
X208971Y90133D01*
X209020Y90302D01*
X209083Y90463D01*
X209154Y90618D01*
X209231Y90766D01*
X209323Y90893D01*
X209330Y90900D01*
X209344Y90914D01*
X209372Y90942D01*
X209407Y90984D01*
X209449Y91026D01*
X209506Y91068D01*
X209576Y91125D01*
X209646Y91174D01*
X209731Y91223D01*
X209822Y91280D01*
X209928Y91322D01*
X210033Y91371D01*
X210153Y91406D01*
X210280Y91434D01*
X210413Y91448D01*
X210554Y91455D01*
X210610D01*
X210653Y91448D01*
D02*
G37*
G36*
X206389Y91512D02*
X206452Y91505D01*
X206530Y91498D01*
X206607Y91491D01*
X206698Y91470D01*
X206888Y91427D01*
X207099Y91364D01*
X207205Y91322D01*
X207303Y91273D01*
X207402Y91209D01*
X207500Y91146D01*
X207507Y91139D01*
X207522Y91132D01*
X207550Y91111D01*
X207585Y91076D01*
X207620Y91040D01*
X207669Y90991D01*
X207719Y90935D01*
X207775Y90879D01*
X207831Y90808D01*
X207887Y90724D01*
X207951Y90639D01*
X208007Y90548D01*
X208056Y90442D01*
X208113Y90337D01*
X208155Y90224D01*
X208197Y90098D01*
X207564Y89950D01*
Y89957D01*
X207557Y89971D01*
X207543Y89999D01*
X207529Y90034D01*
X207514Y90077D01*
X207493Y90133D01*
X207437Y90245D01*
X207367Y90372D01*
X207282Y90499D01*
X207177Y90618D01*
X207064Y90724D01*
X207050Y90738D01*
X207008Y90766D01*
X206938Y90801D01*
X206846Y90850D01*
X206726Y90893D01*
X206593Y90935D01*
X206431Y90963D01*
X206255Y90970D01*
X206199D01*
X206164Y90963D01*
X206114D01*
X206058Y90956D01*
X205924Y90935D01*
X205777Y90907D01*
X205622Y90857D01*
X205460Y90787D01*
X205312Y90696D01*
X205305D01*
X205298Y90682D01*
X205249Y90646D01*
X205186Y90590D01*
X205108Y90506D01*
X205017Y90400D01*
X204932Y90281D01*
X204855Y90133D01*
X204785Y89971D01*
Y89964D01*
X204778Y89950D01*
X204771Y89929D01*
X204764Y89894D01*
X204750Y89851D01*
X204735Y89802D01*
X204714Y89683D01*
X204686Y89542D01*
X204658Y89387D01*
X204644Y89218D01*
X204637Y89035D01*
Y89028D01*
Y89007D01*
Y88972D01*
Y88930D01*
X204644Y88880D01*
Y88817D01*
X204651Y88747D01*
X204658Y88669D01*
X204679Y88500D01*
X204714Y88317D01*
X204757Y88135D01*
X204813Y87952D01*
Y87945D01*
X204820Y87931D01*
X204834Y87909D01*
X204848Y87874D01*
X204890Y87790D01*
X204953Y87691D01*
X205031Y87579D01*
X205129Y87459D01*
X205242Y87354D01*
X205376Y87255D01*
X205383D01*
X205397Y87248D01*
X205418Y87234D01*
X205446Y87220D01*
X205481Y87206D01*
X205523Y87185D01*
X205622Y87142D01*
X205749Y87100D01*
X205889Y87065D01*
X206044Y87037D01*
X206206Y87030D01*
X206255D01*
X206297Y87037D01*
X206347D01*
X206396Y87044D01*
X206523Y87072D01*
X206670Y87107D01*
X206818Y87164D01*
X206973Y87241D01*
X207050Y87283D01*
X207120Y87340D01*
X207128Y87347D01*
X207135Y87354D01*
X207156Y87375D01*
X207184Y87396D01*
X207212Y87431D01*
X207247Y87473D01*
X207289Y87515D01*
X207325Y87572D01*
X207367Y87635D01*
X207416Y87705D01*
X207458Y87776D01*
X207500Y87860D01*
X207536Y87952D01*
X207571Y88050D01*
X207606Y88156D01*
X207634Y88268D01*
X208281Y88106D01*
Y88099D01*
X208274Y88071D01*
X208260Y88029D01*
X208239Y87973D01*
X208218Y87909D01*
X208190Y87832D01*
X208155Y87748D01*
X208113Y87656D01*
X208014Y87459D01*
X207887Y87262D01*
X207810Y87164D01*
X207733Y87065D01*
X207648Y86981D01*
X207550Y86896D01*
X207543Y86889D01*
X207529Y86875D01*
X207493Y86861D01*
X207458Y86833D01*
X207402Y86798D01*
X207346Y86763D01*
X207268Y86727D01*
X207191Y86692D01*
X207099Y86650D01*
X207001Y86615D01*
X206895Y86580D01*
X206783Y86545D01*
X206663Y86516D01*
X206537Y86502D01*
X206403Y86488D01*
X206262Y86481D01*
X206185D01*
X206129Y86488D01*
X206065D01*
X205988Y86495D01*
X205903Y86509D01*
X205805Y86523D01*
X205601Y86559D01*
X205390Y86615D01*
X205179Y86692D01*
X205080Y86742D01*
X204982Y86798D01*
X204975Y86805D01*
X204960Y86812D01*
X204932Y86833D01*
X204904Y86861D01*
X204862Y86889D01*
X204813Y86931D01*
X204757Y86981D01*
X204700Y87037D01*
X204644Y87100D01*
X204581Y87164D01*
X204454Y87325D01*
X204334Y87515D01*
X204229Y87726D01*
Y87734D01*
X204215Y87755D01*
X204208Y87790D01*
X204187Y87832D01*
X204172Y87888D01*
X204151Y87959D01*
X204123Y88036D01*
X204102Y88120D01*
X204081Y88212D01*
X204053Y88317D01*
X204018Y88536D01*
X203990Y88782D01*
X203976Y89035D01*
Y89042D01*
Y89070D01*
Y89113D01*
X203983Y89162D01*
Y89232D01*
X203990Y89303D01*
X203997Y89394D01*
X204011Y89486D01*
X204046Y89690D01*
X204095Y89915D01*
X204165Y90140D01*
X204264Y90358D01*
X204271Y90365D01*
X204278Y90386D01*
X204292Y90414D01*
X204320Y90449D01*
X204348Y90499D01*
X204384Y90555D01*
X204475Y90682D01*
X204595Y90822D01*
X204735Y90963D01*
X204897Y91104D01*
X205087Y91223D01*
X205094Y91230D01*
X205115Y91237D01*
X205144Y91251D01*
X205179Y91273D01*
X205235Y91294D01*
X205291Y91315D01*
X205362Y91343D01*
X205439Y91371D01*
X205523Y91399D01*
X205615Y91427D01*
X205812Y91470D01*
X206037Y91505D01*
X206269Y91519D01*
X206339D01*
X206389Y91512D01*
D02*
G37*
G36*
X55226Y343894D02*
X55220Y343847D01*
Y343794D01*
X55214Y343671D01*
X55196Y343541D01*
X55179Y343401D01*
X55149Y343272D01*
X55132Y343207D01*
X55114Y343154D01*
Y343148D01*
X55108Y343143D01*
X55091Y343107D01*
X55067Y343055D01*
X55026Y342990D01*
X54973Y342920D01*
X54903Y342843D01*
X54821Y342773D01*
X54727Y342702D01*
X54721D01*
X54715Y342697D01*
X54680Y342673D01*
X54621Y342650D01*
X54545Y342614D01*
X54457Y342585D01*
X54351Y342556D01*
X54240Y342538D01*
X54117Y342532D01*
X54111D01*
X54099D01*
X54075D01*
X54046Y342538D01*
X54005D01*
X53964Y342544D01*
X53864Y342567D01*
X53747Y342603D01*
X53624Y342650D01*
X53500Y342720D01*
X53442Y342767D01*
X53383Y342814D01*
X53377Y342820D01*
X53371Y342826D01*
X53354Y342843D01*
X53336Y342867D01*
X53313Y342896D01*
X53289Y342931D01*
X53260Y342978D01*
X53225Y343025D01*
X53195Y343084D01*
X53166Y343148D01*
X53131Y343219D01*
X53102Y343295D01*
X53078Y343383D01*
X53049Y343471D01*
X53031Y343571D01*
X53014Y343676D01*
X53008Y343665D01*
X52996Y343641D01*
X52972Y343606D01*
X52949Y343559D01*
X52884Y343453D01*
X52843Y343401D01*
X52808Y343354D01*
X52796Y343342D01*
X52767Y343313D01*
X52720Y343266D01*
X52661Y343207D01*
X52579Y343143D01*
X52491Y343066D01*
X52386Y342990D01*
X52268Y342908D01*
X51165Y342210D01*
Y342878D01*
X52010Y343412D01*
X52016D01*
X52028Y343424D01*
X52045Y343436D01*
X52069Y343453D01*
X52133Y343494D01*
X52216Y343547D01*
X52304Y343612D01*
X52397Y343676D01*
X52485Y343741D01*
X52568Y343800D01*
X52573Y343806D01*
X52597Y343823D01*
X52632Y343852D01*
X52673Y343894D01*
X52761Y343982D01*
X52802Y344029D01*
X52838Y344075D01*
X52843Y344081D01*
X52849Y344093D01*
X52861Y344117D01*
X52879Y344152D01*
X52896Y344187D01*
X52914Y344228D01*
X52943Y344322D01*
Y344328D01*
X52949Y344339D01*
Y344363D01*
X52955Y344392D01*
X52961Y344433D01*
Y344480D01*
X52967Y344545D01*
Y345237D01*
X51165D01*
Y345777D01*
X55226D01*
Y343894D01*
D02*
G37*
G36*
X53970Y341887D02*
X54023Y341881D01*
X54087Y341875D01*
X54152Y341863D01*
X54228Y341846D01*
X54381Y341805D01*
X54463Y341775D01*
X54551Y341740D01*
X54633Y341699D01*
X54709Y341646D01*
X54791Y341594D01*
X54862Y341529D01*
X54868Y341523D01*
X54879Y341511D01*
X54897Y341494D01*
X54920Y341464D01*
X54950Y341429D01*
X54985Y341382D01*
X55014Y341335D01*
X55055Y341277D01*
X55091Y341218D01*
X55120Y341148D01*
X55184Y340989D01*
X55208Y340907D01*
X55226Y340813D01*
X55237Y340719D01*
X55243Y340620D01*
Y340578D01*
X55237Y340549D01*
Y340520D01*
X55231Y340479D01*
X55214Y340379D01*
X55190Y340267D01*
X55149Y340144D01*
X55097Y340021D01*
X55026Y339898D01*
Y339892D01*
X55014Y339886D01*
X55003Y339869D01*
X54985Y339845D01*
X54938Y339786D01*
X54873Y339710D01*
X54785Y339634D01*
X54680Y339546D01*
X54557Y339469D01*
X54416Y339399D01*
X54410D01*
X54398Y339393D01*
X54375Y339381D01*
X54345Y339370D01*
X54304Y339358D01*
X54252Y339340D01*
X54193Y339329D01*
X54128Y339311D01*
X54052Y339294D01*
X53964Y339276D01*
X53870Y339264D01*
X53770Y339252D01*
X53659Y339241D01*
X53542Y339229D01*
X53412Y339223D01*
X53278D01*
X53272D01*
X53242D01*
X53201D01*
X53148D01*
X53084Y339229D01*
X53008D01*
X52920Y339235D01*
X52832Y339246D01*
X52632Y339264D01*
X52421Y339294D01*
X52221Y339335D01*
X52122Y339364D01*
X52034Y339393D01*
X52028D01*
X52016Y339399D01*
X51993Y339411D01*
X51957Y339423D01*
X51922Y339440D01*
X51875Y339464D01*
X51775Y339522D01*
X51664Y339593D01*
X51547Y339675D01*
X51435Y339781D01*
X51336Y339898D01*
Y339904D01*
X51324Y339915D01*
X51312Y339933D01*
X51300Y339957D01*
X51283Y339992D01*
X51259Y340027D01*
X51236Y340074D01*
X51218Y340121D01*
X51171Y340232D01*
X51130Y340367D01*
X51107Y340514D01*
X51095Y340678D01*
Y340725D01*
X51101Y340755D01*
Y340796D01*
X51107Y340843D01*
X51130Y340954D01*
X51159Y341077D01*
X51206Y341206D01*
X51271Y341335D01*
X51312Y341400D01*
X51359Y341459D01*
X51365Y341464D01*
X51371Y341470D01*
X51388Y341488D01*
X51406Y341506D01*
X51435Y341529D01*
X51470Y341558D01*
X51553Y341617D01*
X51658Y341676D01*
X51787Y341734D01*
X51934Y341781D01*
X52104Y341816D01*
X52145Y341335D01*
X52139D01*
X52128Y341329D01*
X52116D01*
X52092Y341324D01*
X52028Y341306D01*
X51957Y341283D01*
X51875Y341253D01*
X51793Y341212D01*
X51717Y341165D01*
X51652Y341106D01*
X51646Y341101D01*
X51629Y341077D01*
X51605Y341036D01*
X51582Y340989D01*
X51553Y340925D01*
X51529Y340848D01*
X51512Y340760D01*
X51506Y340667D01*
Y340625D01*
X51512Y340584D01*
X51517Y340532D01*
X51529Y340467D01*
X51547Y340402D01*
X51570Y340332D01*
X51605Y340267D01*
X51611Y340262D01*
X51623Y340238D01*
X51646Y340203D01*
X51682Y340168D01*
X51723Y340121D01*
X51770Y340074D01*
X51823Y340027D01*
X51887Y339980D01*
X51893Y339974D01*
X51922Y339962D01*
X51963Y339939D01*
X52016Y339915D01*
X52087Y339886D01*
X52169Y339857D01*
X52263Y339827D01*
X52368Y339798D01*
X52374D01*
X52380Y339792D01*
X52397D01*
X52421Y339786D01*
X52480Y339775D01*
X52556Y339757D01*
X52650Y339745D01*
X52750Y339734D01*
X52861Y339728D01*
X52978Y339722D01*
X52984D01*
X53002D01*
X53031D01*
X53078D01*
X53066Y339728D01*
X53037Y339751D01*
X52996Y339786D01*
X52937Y339827D01*
X52879Y339886D01*
X52814Y339957D01*
X52750Y340039D01*
X52691Y340132D01*
X52685Y340144D01*
X52667Y340179D01*
X52644Y340232D01*
X52620Y340297D01*
X52591Y340385D01*
X52568Y340479D01*
X52550Y340584D01*
X52544Y340696D01*
Y340743D01*
X52550Y340778D01*
X52556Y340825D01*
X52562Y340872D01*
X52573Y340930D01*
X52591Y340989D01*
X52632Y341124D01*
X52661Y341194D01*
X52697Y341265D01*
X52738Y341341D01*
X52791Y341412D01*
X52843Y341482D01*
X52908Y341547D01*
X52914Y341552D01*
X52926Y341564D01*
X52943Y341576D01*
X52972Y341599D01*
X53014Y341629D01*
X53055Y341658D01*
X53107Y341687D01*
X53166Y341717D01*
X53231Y341752D01*
X53301Y341781D01*
X53383Y341811D01*
X53465Y341840D01*
X53559Y341863D01*
X53659Y341875D01*
X53759Y341887D01*
X53870Y341893D01*
X53876D01*
X53899D01*
X53929D01*
X53970Y341887D01*
D02*
G37*
G36*
X30274Y143584D02*
X30268Y143578D01*
X30256Y143567D01*
X30233Y143543D01*
X30210Y143508D01*
X30174Y143467D01*
X30127Y143420D01*
X30080Y143361D01*
X30028Y143291D01*
X29975Y143220D01*
X29910Y143138D01*
X29846Y143044D01*
X29781Y142950D01*
X29711Y142845D01*
X29640Y142733D01*
X29570Y142610D01*
X29499Y142487D01*
X29494Y142481D01*
X29482Y142458D01*
X29464Y142422D01*
X29435Y142370D01*
X29406Y142305D01*
X29370Y142235D01*
X29329Y142153D01*
X29288Y142059D01*
X29241Y141953D01*
X29188Y141847D01*
X29142Y141730D01*
X29095Y141607D01*
X29001Y141355D01*
X28913Y141085D01*
Y141079D01*
X28907Y141061D01*
X28901Y141032D01*
X28889Y140997D01*
X28878Y140950D01*
X28866Y140891D01*
X28848Y140827D01*
X28837Y140756D01*
X28819Y140674D01*
X28801Y140586D01*
X28772Y140398D01*
X28743Y140193D01*
X28725Y139970D01*
X28214D01*
Y139976D01*
Y139993D01*
Y140017D01*
X28220Y140052D01*
Y140099D01*
X28226Y140158D01*
X28232Y140222D01*
X28238Y140293D01*
X28250Y140375D01*
X28261Y140457D01*
X28279Y140557D01*
X28297Y140656D01*
X28314Y140762D01*
X28338Y140879D01*
X28396Y141120D01*
Y141126D01*
X28402Y141149D01*
X28414Y141184D01*
X28432Y141237D01*
X28449Y141296D01*
X28473Y141366D01*
X28496Y141448D01*
X28531Y141537D01*
X28567Y141636D01*
X28602Y141736D01*
X28690Y141959D01*
X28795Y142194D01*
X28913Y142428D01*
X28919Y142434D01*
X28930Y142458D01*
X28948Y142487D01*
X28971Y142534D01*
X29001Y142587D01*
X29042Y142651D01*
X29083Y142722D01*
X29130Y142798D01*
X29241Y142968D01*
X29359Y143144D01*
X29494Y143326D01*
X29634Y143496D01*
X27645D01*
Y143977D01*
X30274D01*
Y143584D01*
D02*
G37*
G36*
X25656Y144024D02*
X25709D01*
X25832Y144018D01*
X25961Y144001D01*
X26102Y143983D01*
X26231Y143954D01*
X26296Y143936D01*
X26349Y143919D01*
X26355D01*
X26360Y143913D01*
X26396Y143895D01*
X26449Y143872D01*
X26513Y143831D01*
X26583Y143778D01*
X26660Y143707D01*
X26730Y143625D01*
X26800Y143531D01*
Y143525D01*
X26806Y143520D01*
X26830Y143484D01*
X26853Y143426D01*
X26888Y143350D01*
X26918Y143261D01*
X26947Y143156D01*
X26965Y143044D01*
X26971Y142921D01*
Y142915D01*
Y142904D01*
Y142880D01*
X26965Y142851D01*
Y142810D01*
X26959Y142769D01*
X26936Y142669D01*
X26900Y142551D01*
X26853Y142428D01*
X26783Y142305D01*
X26736Y142246D01*
X26689Y142188D01*
X26683Y142182D01*
X26677Y142176D01*
X26660Y142158D01*
X26636Y142141D01*
X26607Y142117D01*
X26572Y142094D01*
X26525Y142065D01*
X26478Y142029D01*
X26419Y142000D01*
X26355Y141971D01*
X26284Y141936D01*
X26208Y141906D01*
X26120Y141883D01*
X26032Y141853D01*
X25932Y141836D01*
X25826Y141818D01*
X25838Y141812D01*
X25862Y141800D01*
X25897Y141777D01*
X25944Y141754D01*
X26049Y141689D01*
X26102Y141648D01*
X26149Y141613D01*
X26161Y141601D01*
X26190Y141572D01*
X26237Y141525D01*
X26296Y141466D01*
X26360Y141384D01*
X26437Y141296D01*
X26513Y141190D01*
X26595Y141073D01*
X27293Y139970D01*
X26625D01*
X26091Y140815D01*
Y140821D01*
X26079Y140832D01*
X26067Y140850D01*
X26049Y140873D01*
X26008Y140938D01*
X25956Y141020D01*
X25891Y141108D01*
X25826Y141202D01*
X25762Y141290D01*
X25703Y141372D01*
X25697Y141378D01*
X25680Y141402D01*
X25650Y141437D01*
X25609Y141478D01*
X25521Y141566D01*
X25475Y141607D01*
X25427Y141642D01*
X25422Y141648D01*
X25410Y141654D01*
X25387Y141666D01*
X25351Y141683D01*
X25316Y141701D01*
X25275Y141718D01*
X25181Y141748D01*
X25175D01*
X25164Y141754D01*
X25140D01*
X25111Y141759D01*
X25070Y141765D01*
X25023D01*
X24958Y141771D01*
X24266D01*
Y139970D01*
X23726D01*
Y144030D01*
X25609D01*
X25656Y144024D01*
D02*
G37*
G36*
X95717Y341133D02*
X95770D01*
X95835Y341127D01*
X95905Y341121D01*
X95981Y341110D01*
X96151Y341080D01*
X96333Y341039D01*
X96527Y340981D01*
X96715Y340899D01*
X96720Y340893D01*
X96738Y340887D01*
X96762Y340875D01*
X96797Y340852D01*
X96838Y340828D01*
X96885Y340799D01*
X96996Y340717D01*
X97114Y340623D01*
X97237Y340499D01*
X97360Y340364D01*
X97466Y340206D01*
X97472Y340200D01*
X97477Y340183D01*
X97489Y340159D01*
X97507Y340124D01*
X97524Y340083D01*
X97548Y340036D01*
X97571Y339977D01*
X97595Y339913D01*
X97618Y339837D01*
X97642Y339760D01*
X97683Y339590D01*
X97712Y339402D01*
X97724Y339302D01*
Y339144D01*
X97718Y339103D01*
Y339050D01*
X97712Y338997D01*
X97700Y338927D01*
X97689Y338857D01*
X97659Y338704D01*
X97612Y338528D01*
X97542Y338358D01*
X97501Y338270D01*
X97454Y338182D01*
X97448Y338176D01*
X97442Y338164D01*
X97424Y338141D01*
X97407Y338106D01*
X97378Y338070D01*
X97342Y338023D01*
X97260Y337924D01*
X97155Y337818D01*
X97025Y337701D01*
X96873Y337589D01*
X96703Y337495D01*
X96697D01*
X96679Y337484D01*
X96656Y337472D01*
X96621Y337460D01*
X96574Y337437D01*
X96521Y337419D01*
X96456Y337396D01*
X96386Y337372D01*
X96310Y337355D01*
X96228Y337331D01*
X96140Y337308D01*
X96046Y337290D01*
X95840Y337267D01*
X95623Y337255D01*
X95617D01*
X95600D01*
X95576D01*
X95541D01*
X95494Y337261D01*
X95441D01*
X95383Y337267D01*
X95324Y337272D01*
X95183Y337290D01*
X95031Y337319D01*
X94872Y337355D01*
X94720Y337407D01*
X94714D01*
X94702Y337413D01*
X94679Y337425D01*
X94655Y337437D01*
X94620Y337454D01*
X94579Y337472D01*
X94485Y337519D01*
X94374Y337583D01*
X94256Y337665D01*
X94139Y337759D01*
X94021Y337865D01*
Y337859D01*
X94010Y337847D01*
X93998Y337830D01*
X93980Y337800D01*
X93957Y337771D01*
X93933Y337730D01*
X93881Y337642D01*
X93816Y337537D01*
X93751Y337419D01*
X93699Y337296D01*
X93646Y337178D01*
X93276Y337337D01*
Y337343D01*
X93282Y337355D01*
X93294Y337378D01*
X93306Y337413D01*
X93323Y337454D01*
X93347Y337501D01*
X93370Y337554D01*
X93399Y337613D01*
X93470Y337742D01*
X93552Y337888D01*
X93658Y338047D01*
X93775Y338211D01*
Y338217D01*
X93763Y338229D01*
X93751Y338258D01*
X93734Y338288D01*
X93716Y338334D01*
X93693Y338381D01*
X93675Y338440D01*
X93652Y338505D01*
X93628Y338575D01*
X93605Y338651D01*
X93564Y338821D01*
X93534Y339009D01*
X93529Y339109D01*
X93523Y339209D01*
Y339262D01*
X93529Y339302D01*
Y339350D01*
X93534Y339408D01*
X93546Y339473D01*
X93558Y339543D01*
X93587Y339696D01*
X93634Y339866D01*
X93699Y340042D01*
X93740Y340124D01*
X93787Y340212D01*
X93793Y340218D01*
X93799Y340230D01*
X93816Y340253D01*
X93834Y340282D01*
X93863Y340323D01*
X93898Y340364D01*
X93980Y340464D01*
X94086Y340576D01*
X94215Y340687D01*
X94362Y340799D01*
X94532Y340899D01*
X94538D01*
X94555Y340910D01*
X94579Y340922D01*
X94614Y340934D01*
X94661Y340951D01*
X94714Y340975D01*
X94778Y340998D01*
X94849Y341016D01*
X94925Y341039D01*
X95007Y341063D01*
X95095Y341080D01*
X95195Y341104D01*
X95400Y341127D01*
X95617Y341139D01*
X95623D01*
X95647D01*
X95676D01*
X95717Y341133D01*
D02*
G37*
G36*
X96650Y336351D02*
X96662Y336339D01*
X96668Y336316D01*
X96685Y336287D01*
X96703Y336251D01*
X96726Y336210D01*
X96785Y336111D01*
X96849Y335993D01*
X96932Y335876D01*
X97025Y335753D01*
X97125Y335630D01*
X97131Y335624D01*
X97137Y335618D01*
X97155Y335600D01*
X97172Y335577D01*
X97231Y335524D01*
X97301Y335453D01*
X97383Y335383D01*
X97477Y335307D01*
X97571Y335242D01*
X97671Y335184D01*
Y334861D01*
X93593D01*
Y335360D01*
X96767D01*
X96762Y335365D01*
X96738Y335395D01*
X96703Y335430D01*
X96662Y335489D01*
X96609Y335553D01*
X96550Y335635D01*
X96486Y335729D01*
X96421Y335835D01*
Y335841D01*
X96415Y335847D01*
X96392Y335882D01*
X96362Y335941D01*
X96327Y336011D01*
X96286Y336093D01*
X96245Y336181D01*
X96204Y336269D01*
X96169Y336357D01*
X96650D01*
Y336351D01*
D02*
G37*
G36*
X49642Y132845D02*
X49694Y132839D01*
X49759Y132833D01*
X49824Y132827D01*
X49900Y132809D01*
X50058Y132774D01*
X50234Y132722D01*
X50322Y132686D01*
X50405Y132645D01*
X50487Y132592D01*
X50569Y132540D01*
X50575Y132534D01*
X50586Y132528D01*
X50610Y132510D01*
X50639Y132481D01*
X50669Y132452D01*
X50710Y132410D01*
X50751Y132364D01*
X50798Y132317D01*
X50844Y132258D01*
X50891Y132188D01*
X50944Y132117D01*
X50991Y132041D01*
X51032Y131953D01*
X51079Y131865D01*
X51114Y131771D01*
X51150Y131665D01*
X50622Y131542D01*
Y131548D01*
X50616Y131560D01*
X50604Y131583D01*
X50592Y131613D01*
X50581Y131648D01*
X50563Y131695D01*
X50516Y131789D01*
X50457Y131894D01*
X50387Y132000D01*
X50299Y132100D01*
X50205Y132188D01*
X50193Y132199D01*
X50158Y132223D01*
X50099Y132252D01*
X50023Y132293D01*
X49923Y132328D01*
X49812Y132364D01*
X49677Y132387D01*
X49530Y132393D01*
X49483D01*
X49454Y132387D01*
X49413D01*
X49366Y132381D01*
X49254Y132364D01*
X49131Y132340D01*
X49002Y132299D01*
X48867Y132240D01*
X48744Y132164D01*
X48738D01*
X48732Y132152D01*
X48691Y132123D01*
X48638Y132076D01*
X48574Y132006D01*
X48498Y131918D01*
X48427Y131818D01*
X48363Y131695D01*
X48304Y131560D01*
Y131554D01*
X48298Y131542D01*
X48292Y131524D01*
X48286Y131495D01*
X48275Y131460D01*
X48263Y131419D01*
X48245Y131319D01*
X48222Y131202D01*
X48198Y131073D01*
X48187Y130932D01*
X48181Y130779D01*
Y130773D01*
Y130756D01*
Y130726D01*
Y130691D01*
X48187Y130650D01*
Y130597D01*
X48193Y130539D01*
X48198Y130474D01*
X48216Y130333D01*
X48245Y130181D01*
X48281Y130028D01*
X48327Y129876D01*
Y129870D01*
X48333Y129858D01*
X48345Y129841D01*
X48357Y129811D01*
X48392Y129741D01*
X48445Y129659D01*
X48509Y129565D01*
X48591Y129465D01*
X48685Y129377D01*
X48797Y129295D01*
X48803D01*
X48814Y129289D01*
X48832Y129277D01*
X48856Y129266D01*
X48885Y129254D01*
X48920Y129236D01*
X49002Y129201D01*
X49108Y129166D01*
X49225Y129136D01*
X49354Y129113D01*
X49489Y129107D01*
X49530D01*
X49565Y129113D01*
X49606D01*
X49648Y129119D01*
X49753Y129142D01*
X49876Y129172D01*
X50000Y129219D01*
X50129Y129283D01*
X50193Y129318D01*
X50252Y129365D01*
X50258Y129371D01*
X50264Y129377D01*
X50281Y129395D01*
X50305Y129412D01*
X50328Y129442D01*
X50357Y129477D01*
X50393Y129512D01*
X50422Y129559D01*
X50457Y129612D01*
X50498Y129670D01*
X50534Y129729D01*
X50569Y129799D01*
X50598Y129876D01*
X50627Y129958D01*
X50657Y130046D01*
X50680Y130140D01*
X51220Y130005D01*
Y129999D01*
X51214Y129976D01*
X51202Y129940D01*
X51185Y129893D01*
X51167Y129841D01*
X51144Y129776D01*
X51114Y129706D01*
X51079Y129629D01*
X50997Y129465D01*
X50891Y129301D01*
X50827Y129219D01*
X50762Y129136D01*
X50692Y129066D01*
X50610Y128996D01*
X50604Y128990D01*
X50592Y128978D01*
X50563Y128966D01*
X50534Y128943D01*
X50487Y128913D01*
X50440Y128884D01*
X50375Y128855D01*
X50311Y128826D01*
X50234Y128790D01*
X50152Y128761D01*
X50064Y128732D01*
X49970Y128702D01*
X49871Y128679D01*
X49765Y128667D01*
X49653Y128655D01*
X49536Y128650D01*
X49472D01*
X49425Y128655D01*
X49372D01*
X49307Y128661D01*
X49237Y128673D01*
X49155Y128685D01*
X48985Y128714D01*
X48808Y128761D01*
X48632Y128826D01*
X48550Y128867D01*
X48468Y128913D01*
X48462Y128919D01*
X48451Y128925D01*
X48427Y128943D01*
X48404Y128966D01*
X48369Y128990D01*
X48327Y129025D01*
X48281Y129066D01*
X48233Y129113D01*
X48187Y129166D01*
X48134Y129219D01*
X48028Y129354D01*
X47928Y129512D01*
X47840Y129688D01*
Y129694D01*
X47829Y129712D01*
X47823Y129741D01*
X47805Y129776D01*
X47793Y129823D01*
X47776Y129882D01*
X47752Y129946D01*
X47735Y130017D01*
X47717Y130093D01*
X47694Y130181D01*
X47664Y130363D01*
X47641Y130568D01*
X47629Y130779D01*
Y130785D01*
Y130809D01*
Y130844D01*
X47635Y130885D01*
Y130944D01*
X47641Y131002D01*
X47647Y131079D01*
X47659Y131155D01*
X47688Y131325D01*
X47729Y131513D01*
X47788Y131700D01*
X47870Y131882D01*
X47876Y131888D01*
X47881Y131906D01*
X47893Y131929D01*
X47917Y131959D01*
X47940Y132000D01*
X47969Y132047D01*
X48046Y132152D01*
X48145Y132270D01*
X48263Y132387D01*
X48398Y132504D01*
X48556Y132604D01*
X48562Y132610D01*
X48580Y132616D01*
X48603Y132628D01*
X48632Y132645D01*
X48679Y132663D01*
X48726Y132680D01*
X48785Y132704D01*
X48850Y132727D01*
X48920Y132751D01*
X48996Y132774D01*
X49161Y132809D01*
X49348Y132839D01*
X49542Y132851D01*
X49601D01*
X49642Y132845D01*
D02*
G37*
G36*
X54177Y132252D02*
X52552D01*
X52335Y131155D01*
X52341Y131161D01*
X52352Y131167D01*
X52370Y131178D01*
X52399Y131196D01*
X52435Y131214D01*
X52476Y131237D01*
X52569Y131284D01*
X52687Y131331D01*
X52816Y131372D01*
X52957Y131401D01*
X53027Y131413D01*
X53156D01*
X53191Y131407D01*
X53238Y131401D01*
X53291Y131395D01*
X53350Y131384D01*
X53414Y131366D01*
X53555Y131325D01*
X53632Y131296D01*
X53708Y131255D01*
X53784Y131214D01*
X53860Y131167D01*
X53931Y131108D01*
X54001Y131043D01*
X54007Y131038D01*
X54019Y131026D01*
X54036Y131008D01*
X54060Y130979D01*
X54089Y130938D01*
X54118Y130897D01*
X54154Y130844D01*
X54189Y130785D01*
X54218Y130721D01*
X54254Y130650D01*
X54283Y130568D01*
X54312Y130486D01*
X54336Y130398D01*
X54353Y130298D01*
X54365Y130198D01*
X54371Y130093D01*
Y130087D01*
Y130069D01*
Y130040D01*
X54365Y129999D01*
X54359Y129952D01*
X54353Y129899D01*
X54342Y129835D01*
X54330Y129770D01*
X54295Y129618D01*
X54236Y129459D01*
X54201Y129377D01*
X54154Y129301D01*
X54107Y129219D01*
X54048Y129142D01*
X54042Y129136D01*
X54030Y129119D01*
X54007Y129095D01*
X53978Y129066D01*
X53937Y129031D01*
X53890Y128984D01*
X53831Y128943D01*
X53766Y128896D01*
X53696Y128849D01*
X53614Y128808D01*
X53526Y128767D01*
X53432Y128726D01*
X53332Y128696D01*
X53221Y128673D01*
X53103Y128655D01*
X52980Y128650D01*
X52927D01*
X52886Y128655D01*
X52839Y128661D01*
X52787Y128667D01*
X52722Y128673D01*
X52658Y128691D01*
X52511Y128726D01*
X52364Y128779D01*
X52288Y128814D01*
X52212Y128855D01*
X52141Y128902D01*
X52071Y128955D01*
X52065Y128960D01*
X52053Y128966D01*
X52042Y128990D01*
X52018Y129013D01*
X51989Y129043D01*
X51959Y129078D01*
X51924Y129125D01*
X51895Y129178D01*
X51860Y129230D01*
X51824Y129295D01*
X51760Y129436D01*
X51707Y129600D01*
X51689Y129688D01*
X51678Y129782D01*
X52200Y129823D01*
Y129817D01*
Y129805D01*
X52206Y129788D01*
X52212Y129758D01*
X52229Y129694D01*
X52253Y129606D01*
X52288Y129518D01*
X52335Y129418D01*
X52393Y129330D01*
X52464Y129248D01*
X52476Y129242D01*
X52499Y129219D01*
X52546Y129189D01*
X52611Y129154D01*
X52681Y129119D01*
X52769Y129089D01*
X52869Y129066D01*
X52980Y129060D01*
X53015D01*
X53039Y129066D01*
X53109Y129072D01*
X53191Y129095D01*
X53291Y129125D01*
X53391Y129172D01*
X53497Y129242D01*
X53544Y129283D01*
X53590Y129330D01*
X53596Y129336D01*
X53602Y129342D01*
X53614Y129359D01*
X53632Y129377D01*
X53673Y129442D01*
X53720Y129524D01*
X53761Y129623D01*
X53802Y129747D01*
X53831Y129893D01*
X53843Y129970D01*
Y130052D01*
Y130058D01*
Y130069D01*
Y130093D01*
X53837Y130122D01*
Y130157D01*
X53831Y130198D01*
X53813Y130292D01*
X53784Y130404D01*
X53743Y130515D01*
X53684Y130621D01*
X53602Y130721D01*
Y130726D01*
X53590Y130732D01*
X53561Y130762D01*
X53508Y130803D01*
X53438Y130850D01*
X53344Y130891D01*
X53238Y130932D01*
X53115Y130961D01*
X53045Y130973D01*
X52933D01*
X52886Y130967D01*
X52828Y130961D01*
X52757Y130944D01*
X52687Y130926D01*
X52611Y130897D01*
X52534Y130862D01*
X52529Y130856D01*
X52505Y130844D01*
X52470Y130815D01*
X52423Y130785D01*
X52376Y130744D01*
X52329Y130691D01*
X52276Y130639D01*
X52235Y130574D01*
X51766Y130639D01*
X52159Y132727D01*
X54177D01*
Y132252D01*
D02*
G37*
G36*
X88415Y381996D02*
X87917D01*
Y385171D01*
X87911Y385165D01*
X87881Y385141D01*
X87846Y385106D01*
X87788Y385065D01*
X87723Y385012D01*
X87641Y384953D01*
X87547Y384889D01*
X87441Y384824D01*
X87435D01*
X87430Y384818D01*
X87394Y384795D01*
X87336Y384766D01*
X87265Y384730D01*
X87183Y384689D01*
X87095Y384648D01*
X87007Y384607D01*
X86919Y384572D01*
Y385053D01*
X86925D01*
X86937Y385065D01*
X86960Y385071D01*
X86989Y385088D01*
X87025Y385106D01*
X87066Y385130D01*
X87165Y385188D01*
X87283Y385253D01*
X87400Y385335D01*
X87523Y385429D01*
X87647Y385528D01*
X87653Y385534D01*
X87658Y385540D01*
X87676Y385558D01*
X87699Y385575D01*
X87752Y385634D01*
X87823Y385704D01*
X87893Y385787D01*
X87969Y385881D01*
X88034Y385974D01*
X88093Y386074D01*
X88415D01*
Y381996D01*
D02*
G37*
G36*
X84584Y386051D02*
X84637D01*
X84760Y386045D01*
X84889Y386027D01*
X85030Y386010D01*
X85159Y385980D01*
X85223Y385963D01*
X85276Y385945D01*
X85282D01*
X85288Y385939D01*
X85323Y385922D01*
X85376Y385898D01*
X85441Y385857D01*
X85511Y385804D01*
X85587Y385734D01*
X85658Y385652D01*
X85728Y385558D01*
Y385552D01*
X85734Y385546D01*
X85757Y385511D01*
X85781Y385452D01*
X85816Y385376D01*
X85845Y385288D01*
X85875Y385182D01*
X85892Y385071D01*
X85898Y384948D01*
Y384942D01*
Y384930D01*
Y384907D01*
X85892Y384877D01*
Y384836D01*
X85886Y384795D01*
X85863Y384695D01*
X85828Y384578D01*
X85781Y384455D01*
X85710Y384332D01*
X85663Y384273D01*
X85617Y384214D01*
X85611Y384208D01*
X85605Y384202D01*
X85587Y384185D01*
X85564Y384167D01*
X85534Y384144D01*
X85499Y384120D01*
X85452Y384091D01*
X85405Y384056D01*
X85347Y384026D01*
X85282Y383997D01*
X85212Y383962D01*
X85135Y383932D01*
X85047Y383909D01*
X84959Y383880D01*
X84860Y383862D01*
X84754Y383844D01*
X84766Y383839D01*
X84789Y383827D01*
X84824Y383803D01*
X84871Y383780D01*
X84977Y383715D01*
X85030Y383674D01*
X85077Y383639D01*
X85089Y383627D01*
X85118Y383598D01*
X85165Y383551D01*
X85223Y383493D01*
X85288Y383410D01*
X85364Y383322D01*
X85441Y383217D01*
X85523Y383099D01*
X86221Y381996D01*
X85552D01*
X85018Y382841D01*
Y382847D01*
X85006Y382859D01*
X84995Y382876D01*
X84977Y382900D01*
X84936Y382964D01*
X84883Y383047D01*
X84819Y383135D01*
X84754Y383228D01*
X84690Y383316D01*
X84631Y383399D01*
X84625Y383405D01*
X84607Y383428D01*
X84578Y383463D01*
X84537Y383504D01*
X84449Y383592D01*
X84402Y383633D01*
X84355Y383669D01*
X84349Y383674D01*
X84337Y383680D01*
X84314Y383692D01*
X84279Y383710D01*
X84244Y383727D01*
X84202Y383745D01*
X84109Y383774D01*
X84103D01*
X84091Y383780D01*
X84067D01*
X84038Y383786D01*
X83997Y383792D01*
X83950D01*
X83886Y383798D01*
X83193D01*
Y381996D01*
X82654D01*
Y386057D01*
X84537D01*
X84584Y386051D01*
D02*
G37*
G36*
X91138Y386068D02*
X91214Y386057D01*
X91302Y386039D01*
X91396Y386016D01*
X91496Y385986D01*
X91590Y385939D01*
X91595D01*
X91601Y385933D01*
X91631Y385916D01*
X91678Y385886D01*
X91736Y385845D01*
X91801Y385787D01*
X91871Y385722D01*
X91936Y385646D01*
X92000Y385558D01*
X92006Y385546D01*
X92030Y385517D01*
X92053Y385464D01*
X92094Y385388D01*
X92129Y385300D01*
X92176Y385200D01*
X92217Y385083D01*
X92253Y384953D01*
Y384948D01*
X92258Y384936D01*
X92264Y384918D01*
X92270Y384889D01*
X92276Y384854D01*
X92282Y384813D01*
X92294Y384760D01*
X92299Y384701D01*
X92311Y384637D01*
X92317Y384566D01*
X92323Y384484D01*
X92335Y384402D01*
X92341Y384308D01*
Y384214D01*
X92346Y384109D01*
Y383997D01*
Y383991D01*
Y383968D01*
Y383927D01*
Y383880D01*
X92341Y383815D01*
Y383745D01*
X92335Y383669D01*
X92329Y383586D01*
X92311Y383399D01*
X92282Y383205D01*
X92247Y383017D01*
X92223Y382929D01*
X92194Y382841D01*
Y382835D01*
X92188Y382824D01*
X92176Y382800D01*
X92165Y382771D01*
X92153Y382730D01*
X92129Y382689D01*
X92082Y382589D01*
X92024Y382483D01*
X91947Y382366D01*
X91860Y382260D01*
X91754Y382161D01*
X91748D01*
X91742Y382149D01*
X91725Y382137D01*
X91701Y382125D01*
X91672Y382108D01*
X91642Y382084D01*
X91554Y382043D01*
X91449Y382002D01*
X91326Y381961D01*
X91179Y381938D01*
X91020Y381926D01*
X90962D01*
X90921Y381932D01*
X90874Y381938D01*
X90815Y381949D01*
X90751Y381961D01*
X90680Y381979D01*
X90610Y382002D01*
X90533Y382026D01*
X90457Y382061D01*
X90381Y382102D01*
X90305Y382149D01*
X90228Y382207D01*
X90158Y382272D01*
X90093Y382342D01*
X90087Y382348D01*
X90076Y382366D01*
X90058Y382395D01*
X90029Y382442D01*
X90000Y382495D01*
X89970Y382565D01*
X89929Y382648D01*
X89894Y382741D01*
X89859Y382847D01*
X89824Y382970D01*
X89788Y383105D01*
X89759Y383258D01*
X89730Y383422D01*
X89712Y383598D01*
X89700Y383792D01*
X89694Y383997D01*
Y384003D01*
Y384026D01*
Y384067D01*
Y384114D01*
X89700Y384179D01*
Y384249D01*
X89706Y384326D01*
X89712Y384414D01*
X89730Y384595D01*
X89759Y384789D01*
X89794Y384983D01*
X89818Y385071D01*
X89841Y385159D01*
Y385165D01*
X89847Y385176D01*
X89859Y385200D01*
X89870Y385229D01*
X89882Y385270D01*
X89906Y385311D01*
X89953Y385411D01*
X90011Y385517D01*
X90087Y385628D01*
X90176Y385740D01*
X90281Y385834D01*
X90287D01*
X90293Y385845D01*
X90310Y385857D01*
X90334Y385869D01*
X90363Y385892D01*
X90399Y385910D01*
X90486Y385957D01*
X90592Y385998D01*
X90715Y386039D01*
X90862Y386062D01*
X91020Y386074D01*
X91073D01*
X91138Y386068D01*
D02*
G37*
G36*
X149714Y97402D02*
X150265D01*
Y96944D01*
X149714D01*
Y95970D01*
X149215D01*
Y96944D01*
X147449D01*
Y97402D01*
X149309Y100030D01*
X149714D01*
Y97402D01*
D02*
G37*
G36*
X145665Y100024D02*
X145718D01*
X145841Y100018D01*
X145970Y100001D01*
X146111Y99983D01*
X146240Y99954D01*
X146305Y99936D01*
X146357Y99919D01*
X146363D01*
X146369Y99913D01*
X146404Y99895D01*
X146457Y99872D01*
X146522Y99831D01*
X146592Y99778D01*
X146669Y99707D01*
X146739Y99625D01*
X146809Y99531D01*
Y99525D01*
X146815Y99520D01*
X146839Y99485D01*
X146862Y99426D01*
X146897Y99349D01*
X146927Y99262D01*
X146956Y99156D01*
X146974Y99044D01*
X146980Y98921D01*
Y98915D01*
Y98904D01*
Y98880D01*
X146974Y98851D01*
Y98810D01*
X146968Y98769D01*
X146944Y98669D01*
X146909Y98552D01*
X146862Y98428D01*
X146792Y98305D01*
X146745Y98246D01*
X146698Y98188D01*
X146692Y98182D01*
X146686Y98176D01*
X146669Y98158D01*
X146645Y98141D01*
X146616Y98117D01*
X146580Y98094D01*
X146534Y98064D01*
X146487Y98029D01*
X146428Y98000D01*
X146363Y97971D01*
X146293Y97935D01*
X146217Y97906D01*
X146129Y97883D01*
X146041Y97853D01*
X145941Y97836D01*
X145835Y97818D01*
X145847Y97812D01*
X145871Y97801D01*
X145906Y97777D01*
X145953Y97754D01*
X146058Y97689D01*
X146111Y97648D01*
X146158Y97613D01*
X146170Y97601D01*
X146199Y97572D01*
X146246Y97525D01*
X146305Y97466D01*
X146369Y97384D01*
X146446Y97296D01*
X146522Y97190D01*
X146604Y97073D01*
X147302Y95970D01*
X146633D01*
X146099Y96815D01*
Y96821D01*
X146088Y96832D01*
X146076Y96850D01*
X146058Y96874D01*
X146017Y96938D01*
X145964Y97020D01*
X145900Y97108D01*
X145835Y97202D01*
X145771Y97290D01*
X145712Y97372D01*
X145706Y97378D01*
X145689Y97402D01*
X145659Y97437D01*
X145618Y97478D01*
X145530Y97566D01*
X145483Y97607D01*
X145436Y97642D01*
X145430Y97648D01*
X145419Y97654D01*
X145395Y97666D01*
X145360Y97683D01*
X145325Y97701D01*
X145284Y97718D01*
X145190Y97748D01*
X145184D01*
X145172Y97754D01*
X145149D01*
X145119Y97759D01*
X145078Y97765D01*
X145031D01*
X144967Y97771D01*
X144275D01*
Y95970D01*
X143735D01*
Y100030D01*
X145618D01*
X145665Y100024D01*
D02*
G37*
G36*
X60007Y102068D02*
X60083Y102057D01*
X60177Y102039D01*
X60282Y102010D01*
X60388Y101974D01*
X60494Y101927D01*
X60500D01*
X60505Y101922D01*
X60541Y101904D01*
X60593Y101869D01*
X60652Y101828D01*
X60722Y101769D01*
X60793Y101705D01*
X60863Y101628D01*
X60922Y101540D01*
X60928Y101529D01*
X60945Y101499D01*
X60969Y101446D01*
X60998Y101382D01*
X61028Y101306D01*
X61051Y101217D01*
X61069Y101118D01*
X61075Y101018D01*
Y101006D01*
Y100971D01*
X61069Y100924D01*
X61057Y100860D01*
X61039Y100783D01*
X61010Y100701D01*
X60975Y100619D01*
X60928Y100537D01*
X60922Y100525D01*
X60904Y100502D01*
X60869Y100461D01*
X60822Y100414D01*
X60764Y100361D01*
X60693Y100302D01*
X60611Y100249D01*
X60511Y100197D01*
X60517D01*
X60529Y100191D01*
X60546Y100185D01*
X60570Y100179D01*
X60634Y100155D01*
X60717Y100120D01*
X60810Y100073D01*
X60904Y100015D01*
X60992Y99938D01*
X61075Y99850D01*
X61080Y99839D01*
X61104Y99803D01*
X61139Y99745D01*
X61174Y99669D01*
X61210Y99575D01*
X61245Y99463D01*
X61268Y99334D01*
X61274Y99193D01*
Y99187D01*
Y99170D01*
Y99140D01*
X61268Y99105D01*
X61262Y99058D01*
X61251Y99005D01*
X61239Y98947D01*
X61227Y98882D01*
X61180Y98742D01*
X61145Y98665D01*
X61110Y98595D01*
X61063Y98518D01*
X61010Y98442D01*
X60951Y98366D01*
X60881Y98295D01*
X60875Y98290D01*
X60863Y98278D01*
X60840Y98260D01*
X60810Y98237D01*
X60775Y98208D01*
X60728Y98178D01*
X60676Y98143D01*
X60611Y98114D01*
X60546Y98078D01*
X60470Y98043D01*
X60394Y98014D01*
X60306Y97985D01*
X60212Y97961D01*
X60112Y97943D01*
X60012Y97932D01*
X59901Y97926D01*
X59848D01*
X59813Y97932D01*
X59766Y97938D01*
X59713Y97943D01*
X59655Y97955D01*
X59590Y97967D01*
X59449Y98002D01*
X59303Y98061D01*
X59226Y98096D01*
X59156Y98137D01*
X59085Y98190D01*
X59015Y98243D01*
X59009Y98249D01*
X58998Y98260D01*
X58980Y98278D01*
X58962Y98301D01*
X58933Y98331D01*
X58904Y98372D01*
X58868Y98413D01*
X58833Y98466D01*
X58798Y98524D01*
X58763Y98583D01*
X58698Y98724D01*
X58645Y98888D01*
X58628Y98976D01*
X58616Y99070D01*
X59115Y99135D01*
Y99129D01*
X59121Y99117D01*
X59127Y99094D01*
X59132Y99064D01*
X59138Y99029D01*
X59150Y98988D01*
X59179Y98900D01*
X59220Y98794D01*
X59273Y98694D01*
X59332Y98601D01*
X59402Y98518D01*
X59414Y98513D01*
X59437Y98489D01*
X59485Y98460D01*
X59543Y98431D01*
X59613Y98395D01*
X59702Y98366D01*
X59801Y98343D01*
X59907Y98337D01*
X59942D01*
X59966Y98343D01*
X60030Y98348D01*
X60112Y98366D01*
X60206Y98395D01*
X60306Y98436D01*
X60406Y98495D01*
X60500Y98577D01*
X60511Y98589D01*
X60541Y98624D01*
X60576Y98677D01*
X60623Y98747D01*
X60670Y98835D01*
X60705Y98935D01*
X60734Y99052D01*
X60746Y99181D01*
Y99187D01*
Y99199D01*
Y99217D01*
X60740Y99240D01*
X60734Y99305D01*
X60717Y99381D01*
X60693Y99475D01*
X60652Y99569D01*
X60593Y99663D01*
X60517Y99751D01*
X60505Y99762D01*
X60476Y99786D01*
X60429Y99821D01*
X60365Y99862D01*
X60282Y99903D01*
X60183Y99938D01*
X60071Y99962D01*
X59948Y99974D01*
X59895D01*
X59854Y99968D01*
X59801Y99962D01*
X59743Y99950D01*
X59672Y99938D01*
X59596Y99921D01*
X59655Y100361D01*
X59684D01*
X59707Y100355D01*
X59784D01*
X59848Y100367D01*
X59925Y100379D01*
X60012Y100396D01*
X60112Y100425D01*
X60206Y100466D01*
X60306Y100519D01*
X60312D01*
X60318Y100525D01*
X60347Y100549D01*
X60388Y100590D01*
X60435Y100642D01*
X60482Y100719D01*
X60523Y100807D01*
X60552Y100906D01*
X60564Y100965D01*
Y101030D01*
Y101036D01*
Y101041D01*
Y101077D01*
X60552Y101124D01*
X60541Y101188D01*
X60517Y101259D01*
X60488Y101335D01*
X60441Y101411D01*
X60376Y101482D01*
X60370Y101487D01*
X60341Y101511D01*
X60300Y101540D01*
X60247Y101575D01*
X60177Y101605D01*
X60095Y101634D01*
X60001Y101658D01*
X59895Y101663D01*
X59848D01*
X59795Y101652D01*
X59725Y101640D01*
X59649Y101616D01*
X59573Y101587D01*
X59490Y101540D01*
X59414Y101482D01*
X59408Y101476D01*
X59385Y101446D01*
X59349Y101405D01*
X59308Y101347D01*
X59267Y101270D01*
X59226Y101176D01*
X59191Y101065D01*
X59168Y100936D01*
X58669Y101024D01*
Y101030D01*
X58675Y101047D01*
X58681Y101071D01*
X58686Y101106D01*
X58698Y101147D01*
X58716Y101194D01*
X58751Y101306D01*
X58810Y101435D01*
X58880Y101564D01*
X58968Y101687D01*
X59080Y101798D01*
X59085Y101804D01*
X59097Y101810D01*
X59115Y101822D01*
X59138Y101839D01*
X59168Y101863D01*
X59209Y101886D01*
X59250Y101910D01*
X59303Y101939D01*
X59420Y101986D01*
X59555Y102033D01*
X59713Y102062D01*
X59795Y102074D01*
X59942D01*
X60007Y102068D01*
D02*
G37*
G36*
X56656Y102051D02*
X56709D01*
X56832Y102045D01*
X56961Y102027D01*
X57102Y102010D01*
X57231Y101980D01*
X57296Y101963D01*
X57349Y101945D01*
X57355D01*
X57361Y101939D01*
X57396Y101922D01*
X57449Y101898D01*
X57513Y101857D01*
X57583Y101804D01*
X57660Y101734D01*
X57730Y101652D01*
X57800Y101558D01*
Y101552D01*
X57806Y101546D01*
X57830Y101511D01*
X57853Y101452D01*
X57888Y101376D01*
X57918Y101288D01*
X57947Y101182D01*
X57965Y101071D01*
X57971Y100948D01*
Y100942D01*
Y100930D01*
Y100906D01*
X57965Y100877D01*
Y100836D01*
X57959Y100795D01*
X57936Y100695D01*
X57900Y100578D01*
X57853Y100455D01*
X57783Y100331D01*
X57736Y100273D01*
X57689Y100214D01*
X57683Y100208D01*
X57677Y100202D01*
X57660Y100185D01*
X57636Y100167D01*
X57607Y100144D01*
X57572Y100120D01*
X57525Y100091D01*
X57478Y100056D01*
X57419Y100026D01*
X57355Y99997D01*
X57284Y99962D01*
X57208Y99932D01*
X57120Y99909D01*
X57032Y99880D01*
X56932Y99862D01*
X56827Y99845D01*
X56838Y99839D01*
X56862Y99827D01*
X56897Y99803D01*
X56944Y99780D01*
X57049Y99715D01*
X57102Y99674D01*
X57149Y99639D01*
X57161Y99627D01*
X57190Y99598D01*
X57237Y99551D01*
X57296Y99493D01*
X57361Y99410D01*
X57437Y99322D01*
X57513Y99217D01*
X57595Y99099D01*
X58293Y97996D01*
X57625D01*
X57091Y98841D01*
Y98847D01*
X57079Y98859D01*
X57067Y98876D01*
X57049Y98900D01*
X57008Y98964D01*
X56956Y99047D01*
X56891Y99135D01*
X56827Y99228D01*
X56762Y99317D01*
X56703Y99399D01*
X56697Y99404D01*
X56680Y99428D01*
X56651Y99463D01*
X56609Y99504D01*
X56521Y99592D01*
X56474Y99633D01*
X56427Y99669D01*
X56422Y99674D01*
X56410Y99680D01*
X56386Y99692D01*
X56351Y99710D01*
X56316Y99727D01*
X56275Y99745D01*
X56181Y99774D01*
X56175D01*
X56164Y99780D01*
X56140D01*
X56111Y99786D01*
X56070Y99792D01*
X56023D01*
X55958Y99798D01*
X55266D01*
Y97996D01*
X54726D01*
Y102057D01*
X56609D01*
X56656Y102051D01*
D02*
G37*
G36*
X65881Y149961D02*
X65382D01*
Y153135D01*
X65376Y153130D01*
X65347Y153106D01*
X65312Y153071D01*
X65253Y153030D01*
X65188Y152977D01*
X65106Y152918D01*
X65012Y152854D01*
X64907Y152789D01*
X64901D01*
X64895Y152783D01*
X64860Y152760D01*
X64801Y152731D01*
X64731Y152695D01*
X64649Y152654D01*
X64561Y152613D01*
X64473Y152572D01*
X64385Y152537D01*
Y153018D01*
X64391D01*
X64402Y153030D01*
X64426Y153036D01*
X64455Y153053D01*
X64490Y153071D01*
X64531Y153094D01*
X64631Y153153D01*
X64749Y153217D01*
X64866Y153300D01*
X64989Y153393D01*
X65112Y153493D01*
X65118Y153499D01*
X65124Y153505D01*
X65142Y153523D01*
X65165Y153540D01*
X65218Y153599D01*
X65288Y153669D01*
X65359Y153751D01*
X65435Y153845D01*
X65500Y153939D01*
X65558Y154039D01*
X65881D01*
Y149961D01*
D02*
G37*
G36*
X62049Y154016D02*
X62102D01*
X62225Y154010D01*
X62355Y153992D01*
X62495Y153974D01*
X62625Y153945D01*
X62689Y153927D01*
X62742Y153910D01*
X62748D01*
X62754Y153904D01*
X62789Y153886D01*
X62842Y153863D01*
X62906Y153822D01*
X62976Y153769D01*
X63053Y153699D01*
X63123Y153617D01*
X63194Y153523D01*
Y153517D01*
X63200Y153511D01*
X63223Y153476D01*
X63246Y153417D01*
X63282Y153341D01*
X63311Y153253D01*
X63340Y153147D01*
X63358Y153036D01*
X63364Y152912D01*
Y152907D01*
Y152895D01*
Y152871D01*
X63358Y152842D01*
Y152801D01*
X63352Y152760D01*
X63329Y152660D01*
X63293Y152543D01*
X63246Y152420D01*
X63176Y152296D01*
X63129Y152238D01*
X63082Y152179D01*
X63076Y152173D01*
X63070Y152167D01*
X63053Y152150D01*
X63029Y152132D01*
X63000Y152109D01*
X62965Y152085D01*
X62918Y152056D01*
X62871Y152021D01*
X62812Y151991D01*
X62748Y151962D01*
X62677Y151927D01*
X62601Y151897D01*
X62513Y151874D01*
X62425Y151845D01*
X62325Y151827D01*
X62220Y151809D01*
X62231Y151804D01*
X62255Y151792D01*
X62290Y151768D01*
X62337Y151745D01*
X62443Y151680D01*
X62495Y151639D01*
X62542Y151604D01*
X62554Y151592D01*
X62583Y151563D01*
X62630Y151516D01*
X62689Y151457D01*
X62754Y151375D01*
X62830Y151287D01*
X62906Y151181D01*
X62988Y151064D01*
X63686Y149961D01*
X63018D01*
X62484Y150806D01*
Y150812D01*
X62472Y150824D01*
X62460Y150841D01*
X62443Y150865D01*
X62401Y150929D01*
X62349Y151011D01*
X62284Y151099D01*
X62220Y151193D01*
X62155Y151281D01*
X62096Y151363D01*
X62091Y151369D01*
X62073Y151393D01*
X62044Y151428D01*
X62003Y151469D01*
X61915Y151557D01*
X61868Y151598D01*
X61821Y151633D01*
X61815Y151639D01*
X61803Y151645D01*
X61780Y151657D01*
X61744Y151674D01*
X61709Y151692D01*
X61668Y151710D01*
X61574Y151739D01*
X61568D01*
X61557Y151745D01*
X61533D01*
X61504Y151751D01*
X61463Y151756D01*
X61416D01*
X61351Y151762D01*
X60659D01*
Y149961D01*
X60119D01*
Y154021D01*
X62003D01*
X62049Y154016D01*
D02*
G37*
G36*
X185471Y360961D02*
X184972D01*
Y364135D01*
X184966Y364129D01*
X184937Y364106D01*
X184902Y364071D01*
X184843Y364030D01*
X184779Y363977D01*
X184697Y363918D01*
X184603Y363854D01*
X184497Y363789D01*
X184491D01*
X184485Y363783D01*
X184450Y363760D01*
X184391Y363731D01*
X184321Y363695D01*
X184239Y363654D01*
X184151Y363613D01*
X184063Y363572D01*
X183975Y363537D01*
Y364018D01*
X183981D01*
X183992Y364030D01*
X184016Y364036D01*
X184045Y364053D01*
X184081Y364071D01*
X184121Y364094D01*
X184221Y364153D01*
X184339Y364217D01*
X184456Y364300D01*
X184579Y364394D01*
X184702Y364493D01*
X184708Y364499D01*
X184714Y364505D01*
X184732Y364523D01*
X184755Y364540D01*
X184808Y364599D01*
X184878Y364669D01*
X184949Y364751D01*
X185025Y364845D01*
X185090Y364939D01*
X185148Y365039D01*
X185471D01*
Y360961D01*
D02*
G37*
G36*
X181159Y361442D02*
X183159D01*
Y360961D01*
X180619D01*
Y365021D01*
X181159D01*
Y361442D01*
D02*
G37*
G36*
X193152Y34287D02*
Y34281D01*
Y34264D01*
Y34240D01*
Y34205D01*
X193146Y34158D01*
Y34111D01*
X193134Y34000D01*
X193122Y33870D01*
X193099Y33736D01*
X193064Y33612D01*
X193022Y33495D01*
Y33489D01*
X193017Y33483D01*
X192999Y33448D01*
X192970Y33401D01*
X192929Y33337D01*
X192870Y33272D01*
X192805Y33202D01*
X192723Y33131D01*
X192629Y33073D01*
X192618Y33067D01*
X192582Y33049D01*
X192530Y33026D01*
X192453Y33002D01*
X192360Y32973D01*
X192254Y32949D01*
X192136Y32932D01*
X192007Y32926D01*
X191955D01*
X191919Y32932D01*
X191873Y32938D01*
X191826Y32943D01*
X191702Y32967D01*
X191573Y33002D01*
X191438Y33055D01*
X191368Y33090D01*
X191303Y33131D01*
X191245Y33178D01*
X191186Y33231D01*
X191180Y33237D01*
X191174Y33243D01*
X191162Y33266D01*
X191145Y33290D01*
X191122Y33319D01*
X191098Y33360D01*
X191075Y33407D01*
X191045Y33460D01*
X191022Y33519D01*
X190998Y33589D01*
X190975Y33659D01*
X190951Y33742D01*
X190940Y33830D01*
X190922Y33929D01*
X190916Y34029D01*
Y34140D01*
X191403Y34211D01*
Y34205D01*
Y34193D01*
Y34170D01*
X191409Y34135D01*
X191415Y34099D01*
Y34058D01*
X191432Y33959D01*
X191450Y33853D01*
X191485Y33747D01*
X191520Y33654D01*
X191544Y33612D01*
X191573Y33577D01*
X191579Y33571D01*
X191603Y33554D01*
X191638Y33524D01*
X191685Y33495D01*
X191749Y33460D01*
X191820Y33436D01*
X191908Y33413D01*
X192002Y33407D01*
X192037D01*
X192072Y33413D01*
X192125Y33419D01*
X192178Y33431D01*
X192236Y33442D01*
X192295Y33466D01*
X192354Y33495D01*
X192360Y33501D01*
X192377Y33513D01*
X192401Y33536D01*
X192436Y33560D01*
X192465Y33601D01*
X192500Y33642D01*
X192530Y33689D01*
X192553Y33747D01*
Y33753D01*
X192565Y33777D01*
X192571Y33818D01*
X192582Y33870D01*
X192594Y33941D01*
X192600Y34029D01*
X192612Y34135D01*
Y34258D01*
Y37057D01*
X193152D01*
Y34287D01*
D02*
G37*
G36*
X195704Y32996D02*
X195205D01*
Y36171D01*
X195199Y36165D01*
X195170Y36141D01*
X195135Y36106D01*
X195076Y36065D01*
X195012Y36012D01*
X194929Y35954D01*
X194835Y35889D01*
X194730Y35824D01*
X194724D01*
X194718Y35819D01*
X194683Y35795D01*
X194624Y35766D01*
X194554Y35731D01*
X194472Y35689D01*
X194384Y35648D01*
X194296Y35607D01*
X194208Y35572D01*
Y36053D01*
X194214D01*
X194225Y36065D01*
X194249Y36071D01*
X194278Y36088D01*
X194313Y36106D01*
X194354Y36130D01*
X194454Y36188D01*
X194571Y36253D01*
X194689Y36335D01*
X194812Y36429D01*
X194935Y36528D01*
X194941Y36534D01*
X194947Y36540D01*
X194965Y36558D01*
X194988Y36575D01*
X195041Y36634D01*
X195111Y36704D01*
X195182Y36787D01*
X195258Y36881D01*
X195322Y36974D01*
X195381Y37074D01*
X195704D01*
Y32996D01*
D02*
G37*
G36*
X143512Y142095D02*
X143565Y142089D01*
X143629Y142083D01*
X143694Y142077D01*
X143770Y142059D01*
X143928Y142024D01*
X144104Y141971D01*
X144192Y141936D01*
X144275Y141895D01*
X144357Y141842D01*
X144439Y141790D01*
X144445Y141784D01*
X144457Y141778D01*
X144480Y141760D01*
X144509Y141731D01*
X144539Y141701D01*
X144580Y141660D01*
X144621Y141614D01*
X144668Y141567D01*
X144715Y141508D01*
X144762Y141438D01*
X144814Y141367D01*
X144861Y141291D01*
X144902Y141203D01*
X144949Y141115D01*
X144985Y141021D01*
X145020Y140915D01*
X144492Y140792D01*
Y140798D01*
X144486Y140810D01*
X144474Y140833D01*
X144462Y140863D01*
X144451Y140898D01*
X144433Y140945D01*
X144386Y141039D01*
X144327Y141144D01*
X144257Y141250D01*
X144169Y141349D01*
X144075Y141438D01*
X144063Y141449D01*
X144028Y141473D01*
X143969Y141502D01*
X143893Y141543D01*
X143793Y141578D01*
X143682Y141614D01*
X143547Y141637D01*
X143400Y141643D01*
X143353D01*
X143324Y141637D01*
X143283D01*
X143236Y141631D01*
X143125Y141614D01*
X143001Y141590D01*
X142872Y141549D01*
X142737Y141490D01*
X142614Y141414D01*
X142608D01*
X142602Y141402D01*
X142561Y141373D01*
X142508Y141326D01*
X142444Y141256D01*
X142368Y141168D01*
X142297Y141068D01*
X142233Y140945D01*
X142174Y140810D01*
Y140804D01*
X142168Y140792D01*
X142162Y140774D01*
X142156Y140745D01*
X142145Y140710D01*
X142133Y140669D01*
X142115Y140569D01*
X142092Y140452D01*
X142068Y140323D01*
X142057Y140182D01*
X142051Y140029D01*
Y140023D01*
Y140006D01*
Y139977D01*
Y139941D01*
X142057Y139900D01*
Y139847D01*
X142063Y139789D01*
X142068Y139724D01*
X142086Y139583D01*
X142115Y139431D01*
X142151Y139278D01*
X142198Y139126D01*
Y139120D01*
X142203Y139108D01*
X142215Y139091D01*
X142227Y139061D01*
X142262Y138991D01*
X142315Y138909D01*
X142379Y138815D01*
X142462Y138715D01*
X142555Y138627D01*
X142667Y138545D01*
X142673D01*
X142684Y138539D01*
X142702Y138527D01*
X142726Y138516D01*
X142755Y138504D01*
X142790Y138486D01*
X142872Y138451D01*
X142978Y138416D01*
X143095Y138386D01*
X143224Y138363D01*
X143359Y138357D01*
X143400D01*
X143435Y138363D01*
X143477D01*
X143518Y138369D01*
X143623Y138392D01*
X143747Y138422D01*
X143870Y138469D01*
X143999Y138533D01*
X144063Y138568D01*
X144122Y138615D01*
X144128Y138621D01*
X144134Y138627D01*
X144151Y138645D01*
X144175Y138662D01*
X144198Y138692D01*
X144228Y138727D01*
X144263Y138762D01*
X144292Y138809D01*
X144327Y138862D01*
X144368Y138920D01*
X144404Y138979D01*
X144439Y139050D01*
X144468Y139126D01*
X144497Y139208D01*
X144527Y139296D01*
X144550Y139390D01*
X145090Y139255D01*
Y139249D01*
X145084Y139226D01*
X145072Y139190D01*
X145055Y139143D01*
X145037Y139091D01*
X145014Y139026D01*
X144985Y138956D01*
X144949Y138879D01*
X144867Y138715D01*
X144762Y138551D01*
X144697Y138469D01*
X144633Y138386D01*
X144562Y138316D01*
X144480Y138246D01*
X144474Y138240D01*
X144462Y138228D01*
X144433Y138216D01*
X144404Y138193D01*
X144357Y138163D01*
X144310Y138134D01*
X144245Y138105D01*
X144181Y138076D01*
X144104Y138040D01*
X144022Y138011D01*
X143934Y137982D01*
X143840Y137952D01*
X143741Y137929D01*
X143635Y137917D01*
X143524Y137905D01*
X143406Y137900D01*
X143342D01*
X143295Y137905D01*
X143242D01*
X143177Y137911D01*
X143107Y137923D01*
X143025Y137935D01*
X142855Y137964D01*
X142679Y138011D01*
X142503Y138076D01*
X142421Y138117D01*
X142338Y138163D01*
X142332Y138169D01*
X142321Y138175D01*
X142297Y138193D01*
X142274Y138216D01*
X142239Y138240D01*
X142198Y138275D01*
X142151Y138316D01*
X142104Y138363D01*
X142057Y138416D01*
X142004Y138469D01*
X141898Y138604D01*
X141798Y138762D01*
X141711Y138938D01*
Y138944D01*
X141699Y138961D01*
X141693Y138991D01*
X141675Y139026D01*
X141664Y139073D01*
X141646Y139132D01*
X141622Y139196D01*
X141605Y139267D01*
X141587Y139343D01*
X141564Y139431D01*
X141535Y139613D01*
X141511Y139818D01*
X141499Y140029D01*
Y140035D01*
Y140059D01*
Y140094D01*
X141505Y140135D01*
Y140194D01*
X141511Y140252D01*
X141517Y140329D01*
X141529Y140405D01*
X141558Y140575D01*
X141599Y140763D01*
X141658Y140950D01*
X141740Y141132D01*
X141746Y141138D01*
X141752Y141156D01*
X141763Y141179D01*
X141787Y141209D01*
X141810Y141250D01*
X141840Y141297D01*
X141916Y141402D01*
X142016Y141520D01*
X142133Y141637D01*
X142268Y141754D01*
X142426Y141854D01*
X142432Y141860D01*
X142450Y141866D01*
X142473Y141878D01*
X142503Y141895D01*
X142549Y141913D01*
X142597Y141930D01*
X142655Y141954D01*
X142720Y141977D01*
X142790Y142001D01*
X142866Y142024D01*
X143031Y142059D01*
X143218Y142089D01*
X143412Y142100D01*
X143471D01*
X143512Y142095D01*
D02*
G37*
G36*
X147642Y139402D02*
X148194D01*
Y138944D01*
X147642D01*
Y137970D01*
X147144D01*
Y138944D01*
X145378D01*
Y139402D01*
X147238Y142030D01*
X147642D01*
Y139402D01*
D02*
G37*
G36*
X143683Y157095D02*
X143736Y157089D01*
X143800Y157083D01*
X143865Y157077D01*
X143941Y157059D01*
X144100Y157024D01*
X144276Y156971D01*
X144364Y156936D01*
X144446Y156895D01*
X144528Y156842D01*
X144610Y156790D01*
X144616Y156784D01*
X144628Y156778D01*
X144651Y156760D01*
X144680Y156731D01*
X144710Y156701D01*
X144751Y156660D01*
X144792Y156614D01*
X144839Y156567D01*
X144886Y156508D01*
X144933Y156438D01*
X144986Y156367D01*
X145033Y156291D01*
X145073Y156203D01*
X145120Y156115D01*
X145156Y156021D01*
X145191Y155915D01*
X144663Y155792D01*
Y155798D01*
X144657Y155810D01*
X144645Y155833D01*
X144634Y155863D01*
X144622Y155898D01*
X144604Y155945D01*
X144557Y156039D01*
X144499Y156144D01*
X144428Y156250D01*
X144340Y156349D01*
X144246Y156438D01*
X144235Y156449D01*
X144199Y156473D01*
X144141Y156502D01*
X144064Y156543D01*
X143965Y156578D01*
X143853Y156614D01*
X143718Y156637D01*
X143572Y156643D01*
X143525D01*
X143495Y156637D01*
X143454D01*
X143407Y156631D01*
X143296Y156614D01*
X143173Y156590D01*
X143043Y156549D01*
X142908Y156490D01*
X142785Y156414D01*
X142779D01*
X142774Y156402D01*
X142732Y156373D01*
X142680Y156326D01*
X142615Y156256D01*
X142539Y156168D01*
X142468Y156068D01*
X142404Y155945D01*
X142345Y155810D01*
Y155804D01*
X142339Y155792D01*
X142333Y155774D01*
X142328Y155745D01*
X142316Y155710D01*
X142304Y155669D01*
X142287Y155569D01*
X142263Y155452D01*
X142240Y155323D01*
X142228Y155182D01*
X142222Y155029D01*
Y155023D01*
Y155006D01*
Y154977D01*
Y154941D01*
X142228Y154900D01*
Y154847D01*
X142234Y154789D01*
X142240Y154724D01*
X142257Y154583D01*
X142287Y154431D01*
X142322Y154278D01*
X142369Y154126D01*
Y154120D01*
X142374Y154108D01*
X142386Y154090D01*
X142398Y154061D01*
X142433Y153991D01*
X142486Y153909D01*
X142550Y153815D01*
X142633Y153715D01*
X142727Y153627D01*
X142838Y153545D01*
X142844D01*
X142856Y153539D01*
X142873Y153527D01*
X142897Y153516D01*
X142926Y153504D01*
X142961Y153486D01*
X143043Y153451D01*
X143149Y153416D01*
X143266Y153386D01*
X143395Y153363D01*
X143530Y153357D01*
X143572D01*
X143607Y153363D01*
X143648D01*
X143689Y153369D01*
X143794Y153392D01*
X143918Y153422D01*
X144041Y153469D01*
X144170Y153533D01*
X144235Y153568D01*
X144293Y153615D01*
X144299Y153621D01*
X144305Y153627D01*
X144323Y153645D01*
X144346Y153662D01*
X144369Y153692D01*
X144399Y153727D01*
X144434Y153762D01*
X144463Y153809D01*
X144499Y153862D01*
X144540Y153920D01*
X144575Y153979D01*
X144610Y154050D01*
X144639Y154126D01*
X144669Y154208D01*
X144698Y154296D01*
X144721Y154390D01*
X145261Y154255D01*
Y154249D01*
X145255Y154226D01*
X145244Y154190D01*
X145226Y154143D01*
X145209Y154090D01*
X145185Y154026D01*
X145156Y153956D01*
X145120Y153879D01*
X145038Y153715D01*
X144933Y153551D01*
X144868Y153469D01*
X144804Y153386D01*
X144733Y153316D01*
X144651Y153246D01*
X144645Y153240D01*
X144634Y153228D01*
X144604Y153216D01*
X144575Y153193D01*
X144528Y153163D01*
X144481Y153134D01*
X144416Y153105D01*
X144352Y153076D01*
X144276Y153040D01*
X144193Y153011D01*
X144105Y152982D01*
X144011Y152952D01*
X143912Y152929D01*
X143806Y152917D01*
X143695Y152905D01*
X143577Y152900D01*
X143513D01*
X143466Y152905D01*
X143413D01*
X143349Y152911D01*
X143278Y152923D01*
X143196Y152935D01*
X143026Y152964D01*
X142850Y153011D01*
X142674Y153076D01*
X142592Y153117D01*
X142509Y153163D01*
X142504Y153169D01*
X142492Y153175D01*
X142468Y153193D01*
X142445Y153216D01*
X142410Y153240D01*
X142369Y153275D01*
X142322Y153316D01*
X142275Y153363D01*
X142228Y153416D01*
X142175Y153469D01*
X142069Y153604D01*
X141970Y153762D01*
X141882Y153938D01*
Y153944D01*
X141870Y153961D01*
X141864Y153991D01*
X141847Y154026D01*
X141835Y154073D01*
X141817Y154132D01*
X141794Y154196D01*
X141776Y154267D01*
X141758Y154343D01*
X141735Y154431D01*
X141706Y154613D01*
X141682Y154818D01*
X141670Y155029D01*
Y155035D01*
Y155059D01*
Y155094D01*
X141676Y155135D01*
Y155194D01*
X141682Y155252D01*
X141688Y155329D01*
X141700Y155405D01*
X141729Y155575D01*
X141770Y155763D01*
X141829Y155950D01*
X141911Y156132D01*
X141917Y156138D01*
X141923Y156156D01*
X141934Y156179D01*
X141958Y156209D01*
X141981Y156250D01*
X142011Y156297D01*
X142087Y156402D01*
X142187Y156520D01*
X142304Y156637D01*
X142439Y156754D01*
X142598Y156854D01*
X142603Y156860D01*
X142621Y156866D01*
X142644Y156878D01*
X142674Y156895D01*
X142721Y156913D01*
X142768Y156930D01*
X142826Y156954D01*
X142891Y156977D01*
X142961Y157001D01*
X143038Y157024D01*
X143202Y157059D01*
X143390Y157089D01*
X143583Y157100D01*
X143642D01*
X143683Y157095D01*
D02*
G37*
G36*
X147115Y157042D02*
X147192Y157030D01*
X147285Y157013D01*
X147391Y156983D01*
X147497Y156948D01*
X147602Y156901D01*
X147608D01*
X147614Y156895D01*
X147649Y156878D01*
X147702Y156842D01*
X147761Y156801D01*
X147831Y156743D01*
X147902Y156678D01*
X147972Y156602D01*
X148031Y156514D01*
X148037Y156502D01*
X148054Y156473D01*
X148078Y156420D01*
X148107Y156355D01*
X148136Y156279D01*
X148160Y156191D01*
X148177Y156091D01*
X148183Y155992D01*
Y155980D01*
Y155945D01*
X148177Y155898D01*
X148166Y155833D01*
X148148Y155757D01*
X148119Y155675D01*
X148083Y155593D01*
X148037Y155511D01*
X148031Y155499D01*
X148013Y155475D01*
X147978Y155434D01*
X147931Y155387D01*
X147872Y155334D01*
X147802Y155276D01*
X147720Y155223D01*
X147620Y155170D01*
X147626D01*
X147638Y155164D01*
X147655Y155158D01*
X147679Y155153D01*
X147743Y155129D01*
X147825Y155094D01*
X147919Y155047D01*
X148013Y154988D01*
X148101Y154912D01*
X148183Y154824D01*
X148189Y154812D01*
X148213Y154777D01*
X148248Y154718D01*
X148283Y154642D01*
X148318Y154548D01*
X148353Y154437D01*
X148377Y154308D01*
X148383Y154167D01*
Y154161D01*
Y154143D01*
Y154114D01*
X148377Y154079D01*
X148371Y154032D01*
X148359Y153979D01*
X148348Y153920D01*
X148336Y153856D01*
X148289Y153715D01*
X148254Y153639D01*
X148218Y153568D01*
X148172Y153492D01*
X148119Y153416D01*
X148060Y153340D01*
X147990Y153269D01*
X147984Y153263D01*
X147972Y153251D01*
X147949Y153234D01*
X147919Y153210D01*
X147884Y153181D01*
X147837Y153152D01*
X147784Y153117D01*
X147720Y153087D01*
X147655Y153052D01*
X147579Y153017D01*
X147503Y152987D01*
X147415Y152958D01*
X147321Y152935D01*
X147221Y152917D01*
X147121Y152905D01*
X147010Y152900D01*
X146957D01*
X146922Y152905D01*
X146875Y152911D01*
X146822Y152917D01*
X146763Y152929D01*
X146699Y152941D01*
X146558Y152976D01*
X146411Y153034D01*
X146335Y153070D01*
X146265Y153111D01*
X146194Y153163D01*
X146124Y153216D01*
X146118Y153222D01*
X146106Y153234D01*
X146089Y153251D01*
X146071Y153275D01*
X146042Y153304D01*
X146012Y153345D01*
X145977Y153386D01*
X145942Y153439D01*
X145907Y153498D01*
X145871Y153557D01*
X145807Y153697D01*
X145754Y153862D01*
X145737Y153950D01*
X145725Y154044D01*
X146223Y154108D01*
Y154102D01*
X146229Y154090D01*
X146235Y154067D01*
X146241Y154038D01*
X146247Y154003D01*
X146259Y153961D01*
X146288Y153874D01*
X146329Y153768D01*
X146382Y153668D01*
X146441Y153574D01*
X146511Y153492D01*
X146523Y153486D01*
X146546Y153463D01*
X146593Y153433D01*
X146652Y153404D01*
X146722Y153369D01*
X146810Y153340D01*
X146910Y153316D01*
X147016Y153310D01*
X147051D01*
X147074Y153316D01*
X147139Y153322D01*
X147221Y153340D01*
X147315Y153369D01*
X147415Y153410D01*
X147514Y153469D01*
X147608Y153551D01*
X147620Y153562D01*
X147649Y153598D01*
X147684Y153651D01*
X147732Y153721D01*
X147778Y153809D01*
X147814Y153909D01*
X147843Y154026D01*
X147855Y154155D01*
Y154161D01*
Y154173D01*
Y154190D01*
X147849Y154214D01*
X147843Y154278D01*
X147825Y154355D01*
X147802Y154448D01*
X147761Y154542D01*
X147702Y154636D01*
X147626Y154724D01*
X147614Y154736D01*
X147585Y154759D01*
X147538Y154795D01*
X147473Y154836D01*
X147391Y154877D01*
X147291Y154912D01*
X147180Y154936D01*
X147057Y154947D01*
X147004D01*
X146963Y154941D01*
X146910Y154936D01*
X146851Y154924D01*
X146781Y154912D01*
X146705Y154894D01*
X146763Y155334D01*
X146793D01*
X146816Y155329D01*
X146892D01*
X146957Y155340D01*
X147033Y155352D01*
X147121Y155370D01*
X147221Y155399D01*
X147315Y155440D01*
X147415Y155493D01*
X147421D01*
X147426Y155499D01*
X147456Y155522D01*
X147497Y155563D01*
X147544Y155616D01*
X147591Y155692D01*
X147632Y155780D01*
X147661Y155880D01*
X147673Y155939D01*
Y156003D01*
Y156009D01*
Y156015D01*
Y156050D01*
X147661Y156097D01*
X147649Y156162D01*
X147626Y156232D01*
X147597Y156308D01*
X147550Y156385D01*
X147485Y156455D01*
X147479Y156461D01*
X147450Y156484D01*
X147409Y156514D01*
X147356Y156549D01*
X147285Y156578D01*
X147203Y156608D01*
X147109Y156631D01*
X147004Y156637D01*
X146957D01*
X146904Y156625D01*
X146834Y156614D01*
X146757Y156590D01*
X146681Y156561D01*
X146599Y156514D01*
X146523Y156455D01*
X146517Y156449D01*
X146493Y156420D01*
X146458Y156379D01*
X146417Y156320D01*
X146376Y156244D01*
X146335Y156150D01*
X146300Y156039D01*
X146276Y155909D01*
X145778Y155997D01*
Y156003D01*
X145784Y156021D01*
X145789Y156044D01*
X145795Y156080D01*
X145807Y156121D01*
X145824Y156168D01*
X145860Y156279D01*
X145918Y156408D01*
X145989Y156537D01*
X146077Y156660D01*
X146188Y156772D01*
X146194Y156778D01*
X146206Y156784D01*
X146223Y156795D01*
X146247Y156813D01*
X146276Y156837D01*
X146317Y156860D01*
X146358Y156883D01*
X146411Y156913D01*
X146529Y156960D01*
X146664Y157007D01*
X146822Y157036D01*
X146904Y157048D01*
X147051D01*
X147115Y157042D01*
D02*
G37*
G36*
X108677Y145095D02*
X108730Y145089D01*
X108794Y145083D01*
X108859Y145077D01*
X108935Y145059D01*
X109094Y145024D01*
X109270Y144971D01*
X109358Y144936D01*
X109440Y144895D01*
X109522Y144842D01*
X109604Y144790D01*
X109610Y144784D01*
X109622Y144778D01*
X109645Y144760D01*
X109674Y144731D01*
X109704Y144701D01*
X109745Y144661D01*
X109786Y144614D01*
X109833Y144567D01*
X109880Y144508D01*
X109927Y144438D01*
X109979Y144367D01*
X110026Y144291D01*
X110068Y144203D01*
X110114Y144115D01*
X110150Y144021D01*
X110185Y143915D01*
X109657Y143792D01*
Y143798D01*
X109651Y143810D01*
X109639Y143833D01*
X109627Y143862D01*
X109616Y143898D01*
X109598Y143945D01*
X109551Y144038D01*
X109493Y144144D01*
X109422Y144250D01*
X109334Y144349D01*
X109240Y144438D01*
X109228Y144449D01*
X109193Y144473D01*
X109135Y144502D01*
X109058Y144543D01*
X108959Y144578D01*
X108847Y144614D01*
X108712Y144637D01*
X108565Y144643D01*
X108518D01*
X108489Y144637D01*
X108448D01*
X108401Y144631D01*
X108290Y144614D01*
X108167Y144590D01*
X108037Y144549D01*
X107902Y144490D01*
X107779Y144414D01*
X107773D01*
X107767Y144402D01*
X107726Y144373D01*
X107674Y144326D01*
X107609Y144256D01*
X107533Y144168D01*
X107462Y144068D01*
X107398Y143945D01*
X107339Y143810D01*
Y143804D01*
X107333Y143792D01*
X107327Y143774D01*
X107322Y143745D01*
X107310Y143710D01*
X107298Y143669D01*
X107281Y143569D01*
X107257Y143452D01*
X107233Y143323D01*
X107222Y143182D01*
X107216Y143029D01*
Y143024D01*
Y143006D01*
Y142977D01*
Y142941D01*
X107222Y142900D01*
Y142847D01*
X107228Y142789D01*
X107233Y142724D01*
X107251Y142583D01*
X107281Y142431D01*
X107316Y142278D01*
X107363Y142126D01*
Y142120D01*
X107368Y142108D01*
X107380Y142091D01*
X107392Y142061D01*
X107427Y141991D01*
X107480Y141909D01*
X107544Y141815D01*
X107627Y141715D01*
X107720Y141627D01*
X107832Y141545D01*
X107838D01*
X107850Y141539D01*
X107867Y141527D01*
X107891Y141516D01*
X107920Y141504D01*
X107955Y141486D01*
X108037Y141451D01*
X108143Y141416D01*
X108260Y141386D01*
X108389Y141363D01*
X108524Y141357D01*
X108565D01*
X108601Y141363D01*
X108642D01*
X108683Y141369D01*
X108788Y141392D01*
X108912Y141422D01*
X109035Y141469D01*
X109164Y141533D01*
X109228Y141568D01*
X109287Y141615D01*
X109293Y141621D01*
X109299Y141627D01*
X109317Y141645D01*
X109340Y141662D01*
X109363Y141692D01*
X109393Y141727D01*
X109428Y141762D01*
X109457Y141809D01*
X109493Y141862D01*
X109534Y141920D01*
X109569Y141979D01*
X109604Y142050D01*
X109633Y142126D01*
X109663Y142208D01*
X109692Y142296D01*
X109715Y142390D01*
X110255Y142255D01*
Y142249D01*
X110249Y142226D01*
X110238Y142190D01*
X110220Y142143D01*
X110202Y142091D01*
X110179Y142026D01*
X110150Y141956D01*
X110114Y141879D01*
X110032Y141715D01*
X109927Y141551D01*
X109862Y141469D01*
X109798Y141386D01*
X109727Y141316D01*
X109645Y141246D01*
X109639Y141240D01*
X109627Y141228D01*
X109598Y141216D01*
X109569Y141193D01*
X109522Y141164D01*
X109475Y141134D01*
X109410Y141105D01*
X109346Y141075D01*
X109270Y141040D01*
X109187Y141011D01*
X109099Y140982D01*
X109005Y140952D01*
X108906Y140929D01*
X108800Y140917D01*
X108689Y140905D01*
X108571Y140899D01*
X108507D01*
X108460Y140905D01*
X108407D01*
X108343Y140911D01*
X108272Y140923D01*
X108190Y140935D01*
X108020Y140964D01*
X107844Y141011D01*
X107668Y141075D01*
X107586Y141117D01*
X107503Y141164D01*
X107498Y141169D01*
X107486Y141175D01*
X107462Y141193D01*
X107439Y141216D01*
X107404Y141240D01*
X107363Y141275D01*
X107316Y141316D01*
X107269Y141363D01*
X107222Y141416D01*
X107169Y141469D01*
X107063Y141604D01*
X106964Y141762D01*
X106876Y141938D01*
Y141944D01*
X106864Y141961D01*
X106858Y141991D01*
X106840Y142026D01*
X106829Y142073D01*
X106811Y142132D01*
X106788Y142196D01*
X106770Y142267D01*
X106752Y142343D01*
X106729Y142431D01*
X106700Y142613D01*
X106676Y142818D01*
X106664Y143029D01*
Y143035D01*
Y143059D01*
Y143094D01*
X106670Y143135D01*
Y143194D01*
X106676Y143252D01*
X106682Y143329D01*
X106694Y143405D01*
X106723Y143575D01*
X106764Y143763D01*
X106823Y143951D01*
X106905Y144132D01*
X106911Y144138D01*
X106917Y144156D01*
X106928Y144179D01*
X106952Y144209D01*
X106975Y144250D01*
X107005Y144297D01*
X107081Y144402D01*
X107181Y144520D01*
X107298Y144637D01*
X107433Y144754D01*
X107591Y144854D01*
X107597Y144860D01*
X107615Y144866D01*
X107638Y144878D01*
X107668Y144895D01*
X107715Y144913D01*
X107762Y144930D01*
X107820Y144954D01*
X107885Y144977D01*
X107955Y145001D01*
X108032Y145024D01*
X108196Y145059D01*
X108384Y145089D01*
X108577Y145100D01*
X108636D01*
X108677Y145095D01*
D02*
G37*
G36*
X112156Y145042D02*
X112203Y145036D01*
X112262Y145030D01*
X112326Y145018D01*
X112391Y145007D01*
X112543Y144966D01*
X112696Y144907D01*
X112772Y144872D01*
X112849Y144831D01*
X112919Y144778D01*
X112984Y144719D01*
X112990Y144713D01*
X113001Y144707D01*
X113013Y144684D01*
X113036Y144661D01*
X113066Y144631D01*
X113095Y144590D01*
X113124Y144549D01*
X113160Y144496D01*
X113218Y144385D01*
X113277Y144244D01*
X113300Y144173D01*
X113312Y144091D01*
X113324Y144009D01*
X113330Y143921D01*
Y143909D01*
Y143880D01*
X113324Y143833D01*
X113318Y143769D01*
X113306Y143698D01*
X113283Y143616D01*
X113259Y143528D01*
X113224Y143440D01*
X113218Y143428D01*
X113207Y143399D01*
X113183Y143352D01*
X113148Y143287D01*
X113101Y143217D01*
X113042Y143129D01*
X112972Y143041D01*
X112890Y142941D01*
X112878Y142930D01*
X112849Y142894D01*
X112819Y142865D01*
X112790Y142836D01*
X112755Y142801D01*
X112708Y142754D01*
X112661Y142707D01*
X112602Y142654D01*
X112543Y142595D01*
X112473Y142531D01*
X112397Y142466D01*
X112315Y142390D01*
X112221Y142313D01*
X112127Y142231D01*
X112121Y142226D01*
X112109Y142214D01*
X112086Y142196D01*
X112057Y142173D01*
X112021Y142137D01*
X111980Y142102D01*
X111886Y142026D01*
X111787Y141938D01*
X111693Y141850D01*
X111611Y141774D01*
X111575Y141744D01*
X111546Y141715D01*
X111540Y141709D01*
X111523Y141692D01*
X111499Y141668D01*
X111470Y141633D01*
X111440Y141592D01*
X111405Y141551D01*
X111335Y141451D01*
X113336D01*
Y140970D01*
X110642D01*
Y140976D01*
Y140999D01*
Y141034D01*
X110648Y141081D01*
X110654Y141134D01*
X110666Y141193D01*
X110678Y141251D01*
X110701Y141316D01*
Y141322D01*
X110707Y141328D01*
X110719Y141363D01*
X110742Y141416D01*
X110778Y141486D01*
X110824Y141568D01*
X110883Y141662D01*
X110948Y141756D01*
X111030Y141856D01*
Y141862D01*
X111041Y141868D01*
X111071Y141903D01*
X111124Y141956D01*
X111200Y142032D01*
X111288Y142120D01*
X111399Y142226D01*
X111534Y142343D01*
X111681Y142466D01*
X111687Y142472D01*
X111710Y142490D01*
X111746Y142519D01*
X111787Y142554D01*
X111840Y142601D01*
X111904Y142654D01*
X111968Y142712D01*
X112045Y142777D01*
X112191Y142918D01*
X112338Y143059D01*
X112409Y143129D01*
X112473Y143200D01*
X112532Y143264D01*
X112579Y143329D01*
Y143334D01*
X112591Y143340D01*
X112602Y143358D01*
X112614Y143381D01*
X112655Y143446D01*
X112702Y143522D01*
X112743Y143616D01*
X112784Y143716D01*
X112808Y143827D01*
X112819Y143933D01*
Y143939D01*
Y143945D01*
X112813Y143980D01*
X112808Y144038D01*
X112790Y144103D01*
X112767Y144185D01*
X112725Y144267D01*
X112673Y144349D01*
X112602Y144432D01*
X112591Y144443D01*
X112561Y144467D01*
X112520Y144496D01*
X112456Y144537D01*
X112373Y144572D01*
X112280Y144608D01*
X112168Y144631D01*
X112045Y144637D01*
X112010D01*
X111986Y144631D01*
X111916Y144625D01*
X111834Y144608D01*
X111746Y144584D01*
X111646Y144543D01*
X111552Y144490D01*
X111464Y144420D01*
X111452Y144408D01*
X111429Y144379D01*
X111393Y144332D01*
X111358Y144262D01*
X111317Y144179D01*
X111282Y144074D01*
X111259Y143956D01*
X111247Y143821D01*
X110736Y143874D01*
Y143880D01*
X110742Y143898D01*
Y143927D01*
X110748Y143968D01*
X110760Y144015D01*
X110772Y144068D01*
X110789Y144132D01*
X110807Y144197D01*
X110854Y144338D01*
X110924Y144479D01*
X110965Y144549D01*
X111018Y144619D01*
X111071Y144684D01*
X111130Y144743D01*
X111135Y144748D01*
X111147Y144754D01*
X111165Y144772D01*
X111194Y144790D01*
X111229Y144813D01*
X111270Y144837D01*
X111317Y144866D01*
X111376Y144895D01*
X111440Y144924D01*
X111511Y144954D01*
X111587Y144977D01*
X111669Y145001D01*
X111757Y145018D01*
X111851Y145036D01*
X111951Y145042D01*
X112057Y145048D01*
X112115D01*
X112156Y145042D01*
D02*
G37*
G36*
X86049Y145095D02*
X86102Y145089D01*
X86167Y145083D01*
X86231Y145077D01*
X86308Y145059D01*
X86466Y145024D01*
X86642Y144971D01*
X86730Y144936D01*
X86812Y144895D01*
X86894Y144842D01*
X86976Y144790D01*
X86982Y144784D01*
X86994Y144778D01*
X87018Y144760D01*
X87047Y144731D01*
X87076Y144701D01*
X87117Y144661D01*
X87158Y144614D01*
X87205Y144567D01*
X87252Y144508D01*
X87299Y144438D01*
X87352Y144367D01*
X87399Y144291D01*
X87440Y144203D01*
X87487Y144115D01*
X87522Y144021D01*
X87557Y143915D01*
X87029Y143792D01*
Y143798D01*
X87023Y143810D01*
X87012Y143833D01*
X87000Y143862D01*
X86988Y143898D01*
X86971Y143945D01*
X86924Y144038D01*
X86865Y144144D01*
X86795Y144250D01*
X86707Y144349D01*
X86613Y144438D01*
X86601Y144449D01*
X86566Y144473D01*
X86507Y144502D01*
X86431Y144543D01*
X86331Y144578D01*
X86220Y144614D01*
X86085Y144637D01*
X85938Y144643D01*
X85891D01*
X85862Y144637D01*
X85821D01*
X85774Y144631D01*
X85662Y144614D01*
X85539Y144590D01*
X85410Y144549D01*
X85275Y144490D01*
X85152Y144414D01*
X85146D01*
X85140Y144402D01*
X85099Y144373D01*
X85046Y144326D01*
X84982Y144256D01*
X84905Y144168D01*
X84835Y144068D01*
X84770Y143945D01*
X84712Y143810D01*
Y143804D01*
X84706Y143792D01*
X84700Y143774D01*
X84694Y143745D01*
X84682Y143710D01*
X84671Y143669D01*
X84653Y143569D01*
X84630Y143452D01*
X84606Y143323D01*
X84594Y143182D01*
X84588Y143029D01*
Y143024D01*
Y143006D01*
Y142977D01*
Y142941D01*
X84594Y142900D01*
Y142847D01*
X84600Y142789D01*
X84606Y142724D01*
X84624Y142583D01*
X84653Y142431D01*
X84688Y142278D01*
X84735Y142126D01*
Y142120D01*
X84741Y142108D01*
X84753Y142091D01*
X84764Y142061D01*
X84800Y141991D01*
X84853Y141909D01*
X84917Y141815D01*
X84999Y141715D01*
X85093Y141627D01*
X85205Y141545D01*
X85210D01*
X85222Y141539D01*
X85240Y141527D01*
X85263Y141516D01*
X85293Y141504D01*
X85328Y141486D01*
X85410Y141451D01*
X85516Y141416D01*
X85633Y141386D01*
X85762Y141363D01*
X85897Y141357D01*
X85938D01*
X85973Y141363D01*
X86014D01*
X86055Y141369D01*
X86161Y141392D01*
X86284Y141422D01*
X86407Y141469D01*
X86537Y141533D01*
X86601Y141568D01*
X86660Y141615D01*
X86666Y141621D01*
X86671Y141627D01*
X86689Y141645D01*
X86713Y141662D01*
X86736Y141692D01*
X86765Y141727D01*
X86800Y141762D01*
X86830Y141809D01*
X86865Y141862D01*
X86906Y141920D01*
X86941Y141979D01*
X86976Y142050D01*
X87006Y142126D01*
X87035Y142208D01*
X87065Y142296D01*
X87088Y142390D01*
X87628Y142255D01*
Y142249D01*
X87622Y142226D01*
X87610Y142190D01*
X87593Y142143D01*
X87575Y142091D01*
X87551Y142026D01*
X87522Y141956D01*
X87487Y141879D01*
X87405Y141715D01*
X87299Y141551D01*
X87235Y141469D01*
X87170Y141386D01*
X87100Y141316D01*
X87018Y141246D01*
X87012Y141240D01*
X87000Y141228D01*
X86971Y141216D01*
X86941Y141193D01*
X86894Y141164D01*
X86847Y141134D01*
X86783Y141105D01*
X86718Y141075D01*
X86642Y141040D01*
X86560Y141011D01*
X86472Y140982D01*
X86378Y140952D01*
X86278Y140929D01*
X86173Y140917D01*
X86061Y140905D01*
X85944Y140899D01*
X85879D01*
X85832Y140905D01*
X85780D01*
X85715Y140911D01*
X85645Y140923D01*
X85562Y140935D01*
X85392Y140964D01*
X85216Y141011D01*
X85040Y141075D01*
X84958Y141117D01*
X84876Y141164D01*
X84870Y141169D01*
X84858Y141175D01*
X84835Y141193D01*
X84811Y141216D01*
X84776Y141240D01*
X84735Y141275D01*
X84688Y141316D01*
X84641Y141363D01*
X84594Y141416D01*
X84542Y141469D01*
X84436Y141604D01*
X84336Y141762D01*
X84248Y141938D01*
Y141944D01*
X84236Y141961D01*
X84231Y141991D01*
X84213Y142026D01*
X84201Y142073D01*
X84184Y142132D01*
X84160Y142196D01*
X84143Y142267D01*
X84125Y142343D01*
X84101Y142431D01*
X84072Y142613D01*
X84049Y142818D01*
X84037Y143029D01*
Y143035D01*
Y143059D01*
Y143094D01*
X84043Y143135D01*
Y143194D01*
X84049Y143252D01*
X84055Y143329D01*
X84066Y143405D01*
X84096Y143575D01*
X84137Y143763D01*
X84195Y143951D01*
X84277Y144132D01*
X84283Y144138D01*
X84289Y144156D01*
X84301Y144179D01*
X84325Y144209D01*
X84348Y144250D01*
X84377Y144297D01*
X84454Y144402D01*
X84553Y144520D01*
X84671Y144637D01*
X84806Y144754D01*
X84964Y144854D01*
X84970Y144860D01*
X84987Y144866D01*
X85011Y144878D01*
X85040Y144895D01*
X85087Y144913D01*
X85134Y144930D01*
X85193Y144954D01*
X85257Y144977D01*
X85328Y145001D01*
X85404Y145024D01*
X85568Y145059D01*
X85756Y145089D01*
X85950Y145100D01*
X86008D01*
X86049Y145095D01*
D02*
G37*
G36*
X89963Y140970D02*
X89464D01*
Y144144D01*
X89458Y144138D01*
X89429Y144115D01*
X89394Y144080D01*
X89335Y144038D01*
X89271Y143986D01*
X89188Y143927D01*
X89095Y143862D01*
X88989Y143798D01*
X88983D01*
X88977Y143792D01*
X88942Y143769D01*
X88883Y143739D01*
X88813Y143704D01*
X88731Y143663D01*
X88643Y143622D01*
X88555Y143581D01*
X88467Y143546D01*
Y144027D01*
X88473D01*
X88484Y144038D01*
X88508Y144044D01*
X88537Y144062D01*
X88573Y144080D01*
X88614Y144103D01*
X88713Y144162D01*
X88831Y144226D01*
X88948Y144308D01*
X89071Y144402D01*
X89194Y144502D01*
X89200Y144508D01*
X89206Y144514D01*
X89224Y144531D01*
X89247Y144549D01*
X89300Y144608D01*
X89370Y144678D01*
X89441Y144760D01*
X89517Y144854D01*
X89582Y144948D01*
X89640Y145048D01*
X89963D01*
Y140970D01*
D02*
G37*
%LPC*%
G36*
X151801Y44720D02*
X150647D01*
Y43257D01*
X151843D01*
X151935Y43264D01*
X152033Y43271D01*
X152132Y43278D01*
X152230Y43292D01*
X152308Y43306D01*
X152322Y43313D01*
X152350Y43320D01*
X152392Y43341D01*
X152449Y43369D01*
X152505Y43397D01*
X152568Y43440D01*
X152631Y43496D01*
X152681Y43552D01*
X152688Y43559D01*
X152702Y43580D01*
X152723Y43622D01*
X152744Y43672D01*
X152765Y43728D01*
X152786Y43798D01*
X152800Y43883D01*
X152807Y43974D01*
Y43988D01*
Y44016D01*
X152800Y44059D01*
X152793Y44115D01*
X152779Y44185D01*
X152758Y44256D01*
X152730Y44326D01*
X152688Y44397D01*
X152681Y44404D01*
X152667Y44425D01*
X152638Y44460D01*
X152603Y44495D01*
X152554Y44537D01*
X152498Y44579D01*
X152427Y44622D01*
X152350Y44650D01*
X152343D01*
X152308Y44664D01*
X152259Y44671D01*
X152181Y44685D01*
X152076Y44699D01*
X151956Y44706D01*
X151801Y44720D01*
D02*
G37*
G36*
X151928Y42680D02*
X150647D01*
Y41005D01*
X152033D01*
X152181Y41012D01*
X152244Y41019D01*
X152301Y41026D01*
X152308D01*
X152336Y41033D01*
X152378Y41040D01*
X152427Y41055D01*
X152547Y41097D01*
X152667Y41153D01*
X152674Y41160D01*
X152695Y41174D01*
X152723Y41195D01*
X152758Y41223D01*
X152793Y41266D01*
X152843Y41308D01*
X152878Y41364D01*
X152920Y41427D01*
X152927Y41434D01*
X152934Y41455D01*
X152948Y41498D01*
X152969Y41547D01*
X152990Y41603D01*
X153004Y41674D01*
X153011Y41758D01*
X153018Y41842D01*
Y41856D01*
Y41885D01*
X153011Y41941D01*
X152997Y42004D01*
X152983Y42075D01*
X152955Y42152D01*
X152920Y42229D01*
X152871Y42307D01*
X152864Y42314D01*
X152843Y42342D01*
X152814Y42377D01*
X152772Y42419D01*
X152716Y42469D01*
X152646Y42518D01*
X152568Y42560D01*
X152477Y42595D01*
X152463Y42602D01*
X152434Y42609D01*
X152371Y42623D01*
X152294Y42638D01*
X152195Y42652D01*
X152076Y42666D01*
X151928Y42680D01*
D02*
G37*
G36*
X162369Y43545D02*
X162327D01*
X162299Y43538D01*
X162221Y43531D01*
X162130Y43510D01*
X162017Y43475D01*
X161898Y43425D01*
X161785Y43355D01*
X161672Y43264D01*
X161658Y43250D01*
X161630Y43214D01*
X161581Y43151D01*
X161532Y43067D01*
X161475Y42968D01*
X161426Y42842D01*
X161384Y42694D01*
X161363Y42532D01*
X163340D01*
Y42539D01*
Y42553D01*
X163333Y42574D01*
Y42602D01*
X163319Y42687D01*
X163298Y42778D01*
X163263Y42891D01*
X163227Y42996D01*
X163171Y43102D01*
X163108Y43193D01*
Y43200D01*
X163094Y43207D01*
X163058Y43250D01*
X162995Y43306D01*
X162911Y43369D01*
X162805Y43433D01*
X162679Y43489D01*
X162531Y43531D01*
X162453Y43538D01*
X162369Y43545D01*
D02*
G37*
G36*
X128710Y58668D02*
X128488D01*
X128433Y58654D01*
X128280Y58640D01*
X128100Y58584D01*
X127878Y58515D01*
X127642Y58390D01*
X127406Y58238D01*
X127295Y58127D01*
X127184Y58016D01*
Y58002D01*
X127157Y57988D01*
X127129Y57947D01*
X127101Y57905D01*
X127004Y57766D01*
X126907Y57572D01*
X126796Y57336D01*
X126699Y57045D01*
X126644Y56712D01*
X126616Y56352D01*
Y56338D01*
Y56310D01*
Y56269D01*
X126630Y56199D01*
Y56116D01*
X126644Y56033D01*
X126685Y55825D01*
X126755Y55589D01*
X126838Y55339D01*
X126976Y55090D01*
X127157Y54868D01*
X127184Y54840D01*
X127254Y54785D01*
X127379Y54688D01*
X127531Y54590D01*
X127739Y54479D01*
X127975Y54382D01*
X128238Y54327D01*
X128530Y54299D01*
X128613D01*
X128668Y54313D01*
X128821Y54327D01*
X129001Y54369D01*
X129223Y54438D01*
X129445Y54535D01*
X129667Y54674D01*
X129875Y54868D01*
X129903Y54896D01*
X129958Y54979D01*
X130041Y55104D01*
X130152Y55284D01*
X130249Y55506D01*
X130333Y55769D01*
X130388Y56088D01*
X130416Y56449D01*
Y56463D01*
Y56490D01*
Y56546D01*
X130402Y56615D01*
Y56712D01*
X130388Y56809D01*
X130346Y57031D01*
X130291Y57295D01*
X130194Y57572D01*
X130055Y57836D01*
X129875Y58071D01*
Y58085D01*
X129847Y58099D01*
X129778Y58169D01*
X129667Y58266D01*
X129514Y58376D01*
X129320Y58474D01*
X129098Y58571D01*
X128849Y58640D01*
X128710Y58668D01*
D02*
G37*
G36*
X107048Y58460D02*
X104829D01*
Y51137D01*
X107103D01*
X107200Y51151D01*
X107408Y51165D01*
X107644Y51179D01*
X107893Y51207D01*
X108143Y51248D01*
X108351Y51304D01*
X108379Y51318D01*
X108448Y51331D01*
X108545Y51373D01*
X108670Y51428D01*
X108809Y51512D01*
X108947Y51595D01*
X109086Y51692D01*
X109225Y51803D01*
X109239Y51831D01*
X109294Y51886D01*
X109377Y51983D01*
X109474Y52122D01*
X109585Y52302D01*
X109710Y52510D01*
X109821Y52746D01*
X109918Y53009D01*
Y53023D01*
X109932Y53051D01*
X109946Y53093D01*
X109960Y53148D01*
X109974Y53218D01*
X110001Y53314D01*
X110029Y53412D01*
X110057Y53523D01*
X110099Y53800D01*
X110140Y54119D01*
X110168Y54479D01*
X110182Y54868D01*
Y54882D01*
Y54937D01*
Y55006D01*
X110168Y55117D01*
Y55242D01*
X110154Y55381D01*
X110140Y55547D01*
X110126Y55714D01*
X110057Y56088D01*
X109974Y56476D01*
X109849Y56837D01*
X109766Y57017D01*
X109683Y57170D01*
Y57184D01*
X109655Y57212D01*
X109627Y57253D01*
X109599Y57309D01*
X109488Y57447D01*
X109350Y57614D01*
X109169Y57794D01*
X108961Y57974D01*
X108726Y58127D01*
X108476Y58252D01*
X108448Y58266D01*
X108379Y58279D01*
X108254Y58321D01*
X108074Y58363D01*
X107852Y58390D01*
X107575Y58432D01*
X107408Y58446D01*
X107228D01*
X107048Y58460D01*
D02*
G37*
G36*
X20679Y105785D02*
X18424D01*
Y98342D01*
X20736D01*
X20834Y98356D01*
X21046Y98370D01*
X21286Y98384D01*
X21539Y98412D01*
X21793Y98455D01*
X22004Y98511D01*
X22033Y98525D01*
X22103Y98539D01*
X22202Y98581D01*
X22329Y98638D01*
X22470Y98722D01*
X22611Y98807D01*
X22752Y98906D01*
X22892Y99018D01*
X22907Y99047D01*
X22963Y99103D01*
X23048Y99202D01*
X23146Y99343D01*
X23259Y99526D01*
X23386Y99737D01*
X23499Y99977D01*
X23597Y100245D01*
Y100259D01*
X23612Y100287D01*
X23626Y100330D01*
X23640Y100386D01*
X23654Y100456D01*
X23682Y100555D01*
X23710Y100654D01*
X23738Y100766D01*
X23781Y101048D01*
X23823Y101373D01*
X23851Y101739D01*
X23865Y102134D01*
Y102148D01*
Y102204D01*
Y102275D01*
X23851Y102388D01*
Y102515D01*
X23837Y102655D01*
X23823Y102825D01*
X23809Y102994D01*
X23738Y103375D01*
X23654Y103769D01*
X23527Y104136D01*
X23442Y104319D01*
X23358Y104474D01*
Y104488D01*
X23330Y104516D01*
X23301Y104559D01*
X23273Y104615D01*
X23160Y104756D01*
X23019Y104925D01*
X22836Y105108D01*
X22625Y105292D01*
X22385Y105447D01*
X22131Y105574D01*
X22103Y105588D01*
X22033Y105602D01*
X21906Y105644D01*
X21723Y105686D01*
X21497Y105715D01*
X21215Y105757D01*
X21046Y105771D01*
X20863D01*
X20679Y105785D01*
D02*
G37*
G36*
X202729Y103701D02*
X200473D01*
Y96257D01*
X202785D01*
X202884Y96271D01*
X203095Y96285D01*
X203335Y96300D01*
X203589Y96328D01*
X203842Y96370D01*
X204054Y96426D01*
X204082Y96440D01*
X204152Y96455D01*
X204251Y96497D01*
X204378Y96553D01*
X204519Y96638D01*
X204660Y96722D01*
X204801Y96821D01*
X204942Y96934D01*
X204956Y96962D01*
X205012Y97018D01*
X205097Y97117D01*
X205196Y97258D01*
X205308Y97441D01*
X205435Y97653D01*
X205548Y97893D01*
X205647Y98160D01*
Y98174D01*
X205661Y98203D01*
X205675Y98245D01*
X205689Y98301D01*
X205703Y98372D01*
X205731Y98470D01*
X205760Y98569D01*
X205788Y98682D01*
X205830Y98964D01*
X205872Y99288D01*
X205900Y99655D01*
X205914Y100049D01*
Y100063D01*
Y100120D01*
Y100190D01*
X205900Y100303D01*
Y100430D01*
X205886Y100571D01*
X205872Y100740D01*
X205858Y100909D01*
X205788Y101290D01*
X205703Y101685D01*
X205576Y102051D01*
X205492Y102234D01*
X205407Y102389D01*
Y102404D01*
X205379Y102432D01*
X205351Y102474D01*
X205322Y102530D01*
X205210Y102671D01*
X205069Y102841D01*
X204885Y103024D01*
X204674Y103207D01*
X204434Y103362D01*
X204181Y103489D01*
X204152Y103503D01*
X204082Y103517D01*
X203955Y103560D01*
X203772Y103602D01*
X203546Y103630D01*
X203264Y103672D01*
X203095Y103686D01*
X202912D01*
X202729Y103701D01*
D02*
G37*
G36*
X70647Y397481D02*
Y394408D01*
X75017D01*
X70647Y397481D01*
D02*
G37*
G36*
X-18432Y327044D02*
X-18446D01*
X-18460D01*
X-18544D01*
X-18671Y327016D01*
X-18827Y326988D01*
X-18996Y326931D01*
X-19179Y326847D01*
X-19362Y326734D01*
X-19545Y326579D01*
X-19560Y326565D01*
X-19616Y326494D01*
X-19686Y326396D01*
X-19771Y326269D01*
X-19856Y326100D01*
X-19926Y325916D01*
X-19982Y325691D01*
X-19997Y325451D01*
Y325338D01*
X-19968Y325211D01*
X-19940Y325042D01*
X-19884Y324859D01*
X-19813Y324662D01*
X-19700Y324478D01*
X-19545Y324295D01*
X-19531Y324281D01*
X-19475Y324225D01*
X-19376Y324154D01*
X-19249Y324084D01*
X-19094Y323999D01*
X-18911Y323929D01*
X-18714Y323872D01*
X-18488Y323858D01*
X-18474D01*
X-18460D01*
X-18375Y323872D01*
X-18248Y323886D01*
X-18093Y323915D01*
X-17910Y323971D01*
X-17727Y324041D01*
X-17529Y324154D01*
X-17360Y324295D01*
X-17346Y324309D01*
X-17290Y324380D01*
X-17219Y324478D01*
X-17149Y324605D01*
X-17064Y324775D01*
X-16994Y324972D01*
X-16938Y325197D01*
X-16923Y325451D01*
Y325479D01*
X-16938Y325564D01*
X-16952Y325691D01*
X-16980Y325860D01*
X-17036Y326043D01*
X-17107Y326227D01*
X-17219Y326424D01*
X-17360Y326593D01*
X-17375Y326607D01*
X-17445Y326664D01*
X-17529Y326734D01*
X-17656Y326819D01*
X-17811Y326903D01*
X-17995Y326974D01*
X-18206Y327030D01*
X-18432Y327044D01*
D02*
G37*
G36*
X-13949Y327439D02*
X-13963D01*
X-13991D01*
X-14033D01*
X-14090Y327425D01*
X-14245Y327411D01*
X-14456Y327368D01*
X-14668Y327298D01*
X-14907Y327199D01*
X-15147Y327058D01*
X-15373Y326861D01*
X-15401Y326833D01*
X-15457Y326762D01*
X-15556Y326635D01*
X-15669Y326466D01*
X-15767Y326255D01*
X-15866Y326001D01*
X-15922Y325719D01*
X-15951Y325409D01*
Y325324D01*
X-15937Y325268D01*
X-15922Y325113D01*
X-15880Y324916D01*
X-15810Y324690D01*
X-15711Y324464D01*
X-15570Y324225D01*
X-15387Y324013D01*
X-15359Y323985D01*
X-15288Y323929D01*
X-15161Y323844D01*
X-15006Y323745D01*
X-14795Y323633D01*
X-14555Y323548D01*
X-14287Y323492D01*
X-13991Y323464D01*
X-13963D01*
X-13907D01*
X-13808Y323478D01*
X-13681Y323492D01*
X-13526Y323520D01*
X-13357Y323562D01*
X-13188Y323619D01*
X-13004Y323689D01*
X-12990Y323703D01*
X-12920Y323731D01*
X-12835Y323788D01*
X-12737Y323872D01*
X-12610Y323971D01*
X-12483Y324098D01*
X-12370Y324239D01*
X-12257Y324408D01*
X-12243Y324436D01*
X-12215Y324493D01*
X-12173Y324591D01*
X-12130Y324718D01*
X-12088Y324873D01*
X-12046Y325056D01*
X-12018Y325254D01*
X-12004Y325451D01*
Y325536D01*
X-12018Y325592D01*
X-12032Y325761D01*
X-12074Y325959D01*
X-12145Y326184D01*
X-12229Y326424D01*
X-12370Y326649D01*
X-12553Y326875D01*
X-12581Y326903D01*
X-12652Y326959D01*
X-12779Y327058D01*
X-12934Y327157D01*
X-13131Y327256D01*
X-13371Y327354D01*
X-13653Y327411D01*
X-13949Y327439D01*
D02*
G37*
G36*
X-18263Y311805D02*
X-18277D01*
X-18291D01*
X-18375Y311791D01*
X-18502Y311777D01*
X-18671Y311749D01*
X-18841Y311678D01*
X-19038Y311594D01*
X-19221Y311467D01*
X-19404Y311298D01*
X-19418Y311270D01*
X-19475Y311199D01*
X-19545Y311086D01*
X-19630Y310903D01*
X-19715Y310692D01*
X-19785Y310410D01*
X-19841Y310085D01*
X-19856Y309705D01*
Y306632D01*
X-16627D01*
Y309536D01*
X-16641Y309705D01*
X-16655Y309902D01*
X-16670Y310128D01*
X-16698Y310353D01*
X-16740Y310579D01*
X-16796Y310776D01*
X-16811Y310804D01*
X-16839Y310861D01*
X-16881Y310945D01*
X-16938Y311058D01*
X-17022Y311185D01*
X-17121Y311312D01*
X-17248Y311439D01*
X-17389Y311537D01*
X-17403Y311551D01*
X-17459Y311580D01*
X-17544Y311622D01*
X-17656Y311678D01*
X-17783Y311721D01*
X-17924Y311763D01*
X-18093Y311791D01*
X-18263Y311805D01*
D02*
G37*
G36*
X-16178Y339812D02*
X-16192D01*
X-16206D01*
X-16291Y339798D01*
X-16418Y339784D01*
X-16587Y339756D01*
X-16756Y339686D01*
X-16953Y339601D01*
X-17137Y339474D01*
X-17320Y339305D01*
X-17334Y339277D01*
X-17390Y339206D01*
X-17461Y339093D01*
X-17545Y338910D01*
X-17630Y338699D01*
X-17701Y338417D01*
X-17757Y338092D01*
X-17771Y337712D01*
Y334639D01*
X-14543D01*
Y337543D01*
X-14557Y337712D01*
X-14571Y337909D01*
X-14585Y338135D01*
X-14613Y338360D01*
X-14655Y338586D01*
X-14712Y338783D01*
X-14726Y338811D01*
X-14754Y338868D01*
X-14797Y338952D01*
X-14853Y339065D01*
X-14937Y339192D01*
X-15036Y339319D01*
X-15163Y339446D01*
X-15304Y339544D01*
X-15318Y339559D01*
X-15374Y339587D01*
X-15459Y339629D01*
X-15572Y339686D01*
X-15699Y339728D01*
X-15840Y339770D01*
X-16009Y339798D01*
X-16178Y339812D01*
D02*
G37*
G36*
X205700Y409258D02*
X202218D01*
Y406636D01*
X202233Y406538D01*
Y406439D01*
X202247Y406326D01*
X202275Y406058D01*
X202331Y405762D01*
X202416Y405466D01*
X202529Y405198D01*
X202599Y405071D01*
X202684Y404973D01*
X202712Y404944D01*
X202768Y404888D01*
X202881Y404804D01*
X203022Y404705D01*
X203205Y404606D01*
X203431Y404522D01*
X203685Y404465D01*
X203981Y404437D01*
X203995D01*
X204009D01*
X204079D01*
X204206Y404451D01*
X204347Y404479D01*
X204502Y404507D01*
X204685Y404564D01*
X204855Y404649D01*
X205024Y404747D01*
X205038Y404761D01*
X205094Y404804D01*
X205165Y404874D01*
X205264Y404959D01*
X205362Y405085D01*
X205447Y405226D01*
X205531Y405382D01*
X205602Y405565D01*
Y405579D01*
X205616Y405635D01*
X205630Y405720D01*
X205658Y405833D01*
X205672Y406002D01*
X205686Y406213D01*
X205700Y406467D01*
Y409258D01*
D02*
G37*
G36*
X197624Y378700D02*
X195368D01*
Y371257D01*
X197680D01*
X197779Y371271D01*
X197990Y371286D01*
X198230Y371300D01*
X198484Y371328D01*
X198737Y371370D01*
X198949Y371426D01*
X198977Y371441D01*
X199048Y371455D01*
X199146Y371497D01*
X199273Y371553D01*
X199414Y371638D01*
X199555Y371722D01*
X199696Y371821D01*
X199837Y371934D01*
X199851Y371962D01*
X199907Y372019D01*
X199992Y372117D01*
X200091Y372258D01*
X200203Y372441D01*
X200330Y372653D01*
X200443Y372892D01*
X200542Y373160D01*
Y373175D01*
X200556Y373203D01*
X200570Y373245D01*
X200584Y373301D01*
X200598Y373372D01*
X200626Y373470D01*
X200655Y373569D01*
X200683Y373682D01*
X200725Y373964D01*
X200767Y374288D01*
X200796Y374655D01*
X200810Y375049D01*
Y375064D01*
Y375120D01*
Y375190D01*
X200796Y375303D01*
Y375430D01*
X200781Y375571D01*
X200767Y375740D01*
X200753Y375909D01*
X200683Y376290D01*
X200598Y376685D01*
X200471Y377051D01*
X200387Y377234D01*
X200302Y377389D01*
Y377404D01*
X200274Y377432D01*
X200246Y377474D01*
X200218Y377530D01*
X200105Y377671D01*
X199964Y377841D01*
X199781Y378024D01*
X199569Y378207D01*
X199329Y378362D01*
X199076Y378489D01*
X199048Y378503D01*
X198977Y378517D01*
X198850Y378559D01*
X198667Y378602D01*
X198441Y378630D01*
X198160Y378672D01*
X197990Y378686D01*
X197807D01*
X197624Y378700D01*
D02*
G37*
G36*
X198930Y340304D02*
X198901D01*
X198831D01*
X198704D01*
X198535Y340290D01*
X198351D01*
X198126Y340276D01*
X197886Y340262D01*
X197633Y340233D01*
X197083Y340163D01*
X196815Y340121D01*
X196561Y340064D01*
X196322Y340008D01*
X196096Y339923D01*
X195899Y339839D01*
X195730Y339740D01*
X195715D01*
X195701Y339712D01*
X195603Y339641D01*
X195476Y339515D01*
X195335Y339359D01*
X195194Y339148D01*
X195067Y338908D01*
X194968Y338640D01*
X194954Y338499D01*
X194940Y338344D01*
Y338260D01*
X194954Y338203D01*
X194982Y338063D01*
X195039Y337865D01*
X195137Y337654D01*
X195278Y337414D01*
X195363Y337301D01*
X195476Y337188D01*
X195588Y337076D01*
X195730Y336963D01*
X195744D01*
X195772Y336935D01*
X195814Y336907D01*
X195884Y336878D01*
X195983Y336822D01*
X196110Y336780D01*
X196251Y336723D01*
X196420Y336667D01*
X196632Y336625D01*
X196857Y336568D01*
X197125Y336512D01*
X197407Y336469D01*
X197745Y336441D01*
X198098Y336413D01*
X198493Y336385D01*
X198930D01*
X198944D01*
X198958D01*
X199028D01*
X199155D01*
X199324Y336399D01*
X199508D01*
X199733Y336413D01*
X199973Y336427D01*
X200240Y336455D01*
X200776Y336526D01*
X201044Y336568D01*
X201298Y336625D01*
X201537Y336681D01*
X201763Y336766D01*
X201960Y336850D01*
X202129Y336949D01*
X202144D01*
X202158Y336977D01*
X202200Y337005D01*
X202256Y337048D01*
X202383Y337174D01*
X202538Y337329D01*
X202679Y337541D01*
X202806Y337780D01*
X202863Y337907D01*
X202905Y338048D01*
X202919Y338203D01*
X202933Y338358D01*
Y338443D01*
X202919Y338499D01*
X202891Y338655D01*
X202848Y338838D01*
X202764Y339049D01*
X202637Y339275D01*
X202552Y339388D01*
X202468Y339500D01*
X202355Y339599D01*
X202228Y339698D01*
X202214D01*
X202186Y339726D01*
X202129Y339754D01*
X202059Y339796D01*
X201946Y339839D01*
X201819Y339895D01*
X201664Y339937D01*
X201481Y339994D01*
X201270Y340050D01*
X201030Y340107D01*
X200762Y340163D01*
X200466Y340205D01*
X200128Y340247D01*
X199761Y340276D01*
X199366Y340290D01*
X198930Y340304D01*
D02*
G37*
G36*
X14011Y413811D02*
X13786D01*
X13730Y413797D01*
X13575Y413783D01*
X13391Y413726D01*
X13166Y413656D01*
X12926Y413529D01*
X12686Y413374D01*
X12574Y413261D01*
X12461Y413148D01*
Y413134D01*
X12433Y413120D01*
X12404Y413078D01*
X12376Y413036D01*
X12278Y412895D01*
X12179Y412697D01*
X12066Y412458D01*
X11967Y412161D01*
X11911Y411823D01*
X11883Y411457D01*
Y411443D01*
Y411414D01*
Y411372D01*
X11897Y411302D01*
Y411217D01*
X11911Y411133D01*
X11953Y410921D01*
X12024Y410681D01*
X12108Y410428D01*
X12249Y410174D01*
X12433Y409948D01*
X12461Y409920D01*
X12531Y409864D01*
X12658Y409765D01*
X12813Y409666D01*
X13025Y409554D01*
X13264Y409455D01*
X13532Y409398D01*
X13828Y409370D01*
X13913D01*
X13969Y409384D01*
X14124Y409398D01*
X14308Y409441D01*
X14533Y409511D01*
X14759Y409610D01*
X14984Y409751D01*
X15196Y409948D01*
X15224Y409977D01*
X15280Y410061D01*
X15365Y410188D01*
X15478Y410371D01*
X15576Y410597D01*
X15661Y410865D01*
X15717Y411189D01*
X15745Y411555D01*
Y411570D01*
Y411598D01*
Y411654D01*
X15731Y411725D01*
Y411823D01*
X15717Y411922D01*
X15675Y412147D01*
X15619Y412415D01*
X15520Y412697D01*
X15379Y412965D01*
X15196Y413205D01*
Y413219D01*
X15167Y413233D01*
X15097Y413303D01*
X14984Y413402D01*
X14829Y413515D01*
X14632Y413614D01*
X14406Y413712D01*
X14152Y413783D01*
X14011Y413811D01*
D02*
G37*
G36*
X139257Y388229D02*
X139214D01*
X139186Y388222D01*
X139116Y388215D01*
X139017Y388194D01*
X138912Y388158D01*
X138792Y388102D01*
X138680Y388032D01*
X138567Y387933D01*
X138553Y387919D01*
X138525Y387884D01*
X138476Y387821D01*
X138426Y387729D01*
X138377Y387624D01*
X138328Y387490D01*
X138300Y387342D01*
X138286Y387173D01*
Y387159D01*
Y387124D01*
X138293Y387061D01*
X138300Y386983D01*
X138314Y386892D01*
X138342Y386793D01*
X138370Y386688D01*
X138412Y386582D01*
X138419Y386568D01*
X138441Y386533D01*
X138469Y386484D01*
X138511Y386421D01*
X138560Y386357D01*
X138623Y386280D01*
X138694Y386216D01*
X138778Y386153D01*
X138792Y386146D01*
X138820Y386132D01*
X138870Y386104D01*
X138933Y386083D01*
X139003Y386055D01*
X139088Y386026D01*
X139179Y386012D01*
X139278Y386005D01*
X139313D01*
X139341Y386012D01*
X139411Y386019D01*
X139503Y386041D01*
X139601Y386083D01*
X139714Y386132D01*
X139827Y386209D01*
X139883Y386252D01*
X139932Y386308D01*
Y386315D01*
X139946Y386322D01*
X139974Y386364D01*
X140016Y386435D01*
X140073Y386526D01*
X140122Y386646D01*
X140164Y386786D01*
X140192Y386948D01*
X140206Y387138D01*
Y387145D01*
Y387159D01*
Y387187D01*
X140199Y387223D01*
Y387265D01*
X140192Y387314D01*
X140171Y387427D01*
X140143Y387553D01*
X140094Y387687D01*
X140024Y387814D01*
X139932Y387933D01*
X139918Y387947D01*
X139883Y387982D01*
X139827Y388025D01*
X139749Y388081D01*
X139651Y388137D01*
X139538Y388179D01*
X139404Y388215D01*
X139257Y388229D01*
D02*
G37*
G36*
X131362Y389924D02*
X129829D01*
Y388313D01*
X131278D01*
X131362Y388320D01*
X131461Y388327D01*
X131574Y388334D01*
X131686Y388348D01*
X131799Y388369D01*
X131897Y388397D01*
X131911Y388405D01*
X131939Y388419D01*
X131982Y388440D01*
X132038Y388468D01*
X132101Y388510D01*
X132165Y388559D01*
X132228Y388623D01*
X132277Y388693D01*
X132284Y388700D01*
X132298Y388728D01*
X132319Y388770D01*
X132347Y388827D01*
X132369Y388890D01*
X132390Y388960D01*
X132404Y389045D01*
X132411Y389129D01*
Y389136D01*
Y389143D01*
X132404Y389186D01*
X132397Y389249D01*
X132383Y389333D01*
X132347Y389418D01*
X132305Y389516D01*
X132242Y389608D01*
X132157Y389699D01*
X132143Y389706D01*
X132108Y389734D01*
X132052Y389770D01*
X131960Y389812D01*
X131855Y389854D01*
X131714Y389889D01*
X131552Y389917D01*
X131362Y389924D01*
D02*
G37*
G36*
X102871Y92393D02*
X102864D01*
X102857D01*
X102815Y92386D01*
X102751Y92379D01*
X102667Y92365D01*
X102582Y92330D01*
X102484Y92288D01*
X102392Y92224D01*
X102301Y92140D01*
X102294Y92126D01*
X102266Y92091D01*
X102231Y92034D01*
X102188Y91943D01*
X102146Y91837D01*
X102111Y91697D01*
X102083Y91535D01*
X102076Y91345D01*
Y89811D01*
X103687D01*
Y91260D01*
X103680Y91345D01*
X103673Y91443D01*
X103666Y91556D01*
X103652Y91669D01*
X103631Y91781D01*
X103603Y91880D01*
X103595Y91894D01*
X103581Y91922D01*
X103560Y91964D01*
X103532Y92020D01*
X103490Y92084D01*
X103441Y92147D01*
X103377Y92210D01*
X103307Y92260D01*
X103300Y92267D01*
X103272Y92281D01*
X103230Y92302D01*
X103173Y92330D01*
X103110Y92351D01*
X103040Y92372D01*
X102955Y92386D01*
X102871Y92393D01*
D02*
G37*
G36*
X120728Y98549D02*
X118547D01*
X120728Y97015D01*
Y98549D01*
D02*
G37*
G36*
X118913Y91421D02*
X118906D01*
X118899D01*
X118857Y91414D01*
X118793Y91407D01*
X118709Y91393D01*
X118624Y91358D01*
X118526Y91316D01*
X118434Y91252D01*
X118343Y91168D01*
X118336Y91154D01*
X118308Y91119D01*
X118273Y91063D01*
X118230Y90971D01*
X118188Y90866D01*
X118153Y90725D01*
X118125Y90563D01*
X118118Y90373D01*
Y88839D01*
X119729D01*
Y90289D01*
X119722Y90373D01*
X119715Y90471D01*
X119708Y90584D01*
X119694Y90697D01*
X119673Y90809D01*
X119645Y90908D01*
X119638Y90922D01*
X119624Y90950D01*
X119602Y90992D01*
X119574Y91048D01*
X119532Y91112D01*
X119483Y91175D01*
X119419Y91238D01*
X119349Y91288D01*
X119342Y91295D01*
X119314Y91309D01*
X119272Y91330D01*
X119215Y91358D01*
X119152Y91379D01*
X119082Y91400D01*
X118997Y91414D01*
X118913Y91421D01*
D02*
G37*
G36*
X88871Y72411D02*
X88864D01*
X88857D01*
X88814Y72404D01*
X88751Y72397D01*
X88667Y72383D01*
X88582Y72347D01*
X88484Y72305D01*
X88392Y72242D01*
X88301Y72158D01*
X88294Y72144D01*
X88266Y72108D01*
X88230Y72052D01*
X88188Y71961D01*
X88146Y71855D01*
X88111Y71714D01*
X88083Y71553D01*
X88076Y71363D01*
Y69829D01*
X89687D01*
Y71278D01*
X89680Y71363D01*
X89673Y71461D01*
X89666Y71574D01*
X89652Y71686D01*
X89631Y71799D01*
X89602Y71897D01*
X89595Y71911D01*
X89581Y71939D01*
X89560Y71982D01*
X89532Y72038D01*
X89490Y72101D01*
X89441Y72165D01*
X89377Y72228D01*
X89307Y72277D01*
X89300Y72284D01*
X89272Y72298D01*
X89230Y72319D01*
X89173Y72347D01*
X89110Y72369D01*
X89040Y72390D01*
X88955Y72404D01*
X88871Y72411D01*
D02*
G37*
G36*
X53913Y78436D02*
X53906D01*
X53899D01*
X53857Y78428D01*
X53793Y78421D01*
X53709Y78407D01*
X53625Y78372D01*
X53526Y78330D01*
X53435Y78267D01*
X53343Y78182D01*
X53336Y78168D01*
X53308Y78133D01*
X53273Y78077D01*
X53231Y77985D01*
X53188Y77880D01*
X53153Y77739D01*
X53125Y77577D01*
X53118Y77387D01*
Y75853D01*
X54729D01*
Y77303D01*
X54722Y77387D01*
X54715Y77486D01*
X54708Y77598D01*
X54694Y77711D01*
X54673Y77823D01*
X54645Y77922D01*
X54638Y77936D01*
X54624Y77964D01*
X54602Y78006D01*
X54574Y78063D01*
X54532Y78126D01*
X54483Y78189D01*
X54419Y78253D01*
X54349Y78302D01*
X54342Y78309D01*
X54314Y78323D01*
X54272Y78344D01*
X54215Y78372D01*
X54152Y78393D01*
X54082Y78414D01*
X53997Y78428D01*
X53913Y78436D01*
D02*
G37*
G36*
X71334Y386841D02*
X69800D01*
Y385229D01*
X71249D01*
X71334Y385236D01*
X71432Y385243D01*
X71545Y385250D01*
X71658Y385265D01*
X71770Y385286D01*
X71869Y385314D01*
X71883Y385321D01*
X71911Y385335D01*
X71953Y385356D01*
X72009Y385384D01*
X72073Y385426D01*
X72136Y385476D01*
X72199Y385539D01*
X72249Y385609D01*
X72256Y385616D01*
X72270Y385644D01*
X72291Y385687D01*
X72319Y385743D01*
X72340Y385806D01*
X72361Y385877D01*
X72375Y385961D01*
X72382Y386045D01*
Y386053D01*
Y386060D01*
X72375Y386102D01*
X72368Y386165D01*
X72354Y386250D01*
X72319Y386334D01*
X72277Y386432D01*
X72213Y386524D01*
X72129Y386615D01*
X72115Y386622D01*
X72080Y386651D01*
X72023Y386686D01*
X71932Y386728D01*
X71826Y386770D01*
X71686Y386805D01*
X71524Y386833D01*
X71334Y386841D01*
D02*
G37*
G36*
X56280Y113882D02*
X54746D01*
Y112271D01*
X56195D01*
X56280Y112278D01*
X56378Y112285D01*
X56491Y112292D01*
X56603Y112306D01*
X56716Y112327D01*
X56814Y112355D01*
X56829Y112362D01*
X56857Y112376D01*
X56899Y112397D01*
X56955Y112426D01*
X57018Y112468D01*
X57082Y112517D01*
X57145Y112580D01*
X57194Y112651D01*
X57201Y112658D01*
X57215Y112686D01*
X57237Y112728D01*
X57265Y112785D01*
X57286Y112848D01*
X57307Y112918D01*
X57321Y113003D01*
X57328Y113087D01*
Y113094D01*
Y113101D01*
X57321Y113143D01*
X57314Y113207D01*
X57300Y113291D01*
X57265Y113376D01*
X57223Y113474D01*
X57159Y113566D01*
X57075Y113657D01*
X57061Y113664D01*
X57026Y113692D01*
X56969Y113727D01*
X56878Y113770D01*
X56772Y113812D01*
X56632Y113847D01*
X56470Y113875D01*
X56280Y113882D01*
D02*
G37*
G36*
X210462Y89197D02*
X210420D01*
X210392Y89190D01*
X210322Y89183D01*
X210223Y89162D01*
X210118Y89127D01*
X209998Y89070D01*
X209886Y89000D01*
X209773Y88902D01*
X209759Y88887D01*
X209731Y88852D01*
X209681Y88789D01*
X209632Y88698D01*
X209583Y88592D01*
X209534Y88458D01*
X209506Y88310D01*
X209492Y88142D01*
Y88128D01*
Y88092D01*
X209499Y88029D01*
X209506Y87952D01*
X209520Y87860D01*
X209548Y87762D01*
X209576Y87656D01*
X209618Y87551D01*
X209625Y87537D01*
X209646Y87501D01*
X209674Y87452D01*
X209717Y87389D01*
X209766Y87325D01*
X209829Y87248D01*
X209900Y87185D01*
X209984Y87121D01*
X209998Y87114D01*
X210026Y87100D01*
X210076Y87072D01*
X210139Y87051D01*
X210209Y87023D01*
X210294Y86995D01*
X210385Y86981D01*
X210484Y86974D01*
X210519D01*
X210547Y86981D01*
X210617Y86988D01*
X210709Y87009D01*
X210807Y87051D01*
X210920Y87100D01*
X211032Y87178D01*
X211089Y87220D01*
X211138Y87276D01*
Y87283D01*
X211152Y87290D01*
X211180Y87332D01*
X211222Y87403D01*
X211279Y87494D01*
X211328Y87614D01*
X211370Y87755D01*
X211398Y87916D01*
X211412Y88106D01*
Y88113D01*
Y88128D01*
Y88156D01*
X211405Y88191D01*
Y88233D01*
X211398Y88282D01*
X211377Y88395D01*
X211349Y88522D01*
X211300Y88655D01*
X211229Y88782D01*
X211138Y88902D01*
X211124Y88916D01*
X211089Y88951D01*
X211032Y88993D01*
X210955Y89049D01*
X210856Y89106D01*
X210744Y89148D01*
X210610Y89183D01*
X210462Y89197D01*
D02*
G37*
G36*
X54774Y345237D02*
X53430D01*
Y344029D01*
X53436Y343958D01*
X53442Y343876D01*
X53448Y343782D01*
X53460Y343688D01*
X53477Y343594D01*
X53500Y343512D01*
X53506Y343500D01*
X53518Y343477D01*
X53536Y343442D01*
X53559Y343395D01*
X53594Y343342D01*
X53636Y343289D01*
X53688Y343236D01*
X53747Y343195D01*
X53753Y343189D01*
X53776Y343178D01*
X53811Y343160D01*
X53858Y343137D01*
X53911Y343119D01*
X53970Y343101D01*
X54040Y343090D01*
X54111Y343084D01*
X54117D01*
X54123D01*
X54158Y343090D01*
X54211Y343096D01*
X54281Y343107D01*
X54351Y343137D01*
X54433Y343172D01*
X54510Y343225D01*
X54586Y343295D01*
X54592Y343307D01*
X54615Y343336D01*
X54645Y343383D01*
X54680Y343459D01*
X54715Y343547D01*
X54744Y343665D01*
X54768Y343800D01*
X54774Y343958D01*
Y345237D01*
D02*
G37*
G36*
X53853Y341382D02*
X53847D01*
X53835D01*
X53817D01*
X53788Y341376D01*
X53753D01*
X53718Y341371D01*
X53630Y341353D01*
X53530Y341324D01*
X53424Y341288D01*
X53319Y341230D01*
X53225Y341153D01*
X53213Y341142D01*
X53190Y341112D01*
X53148Y341060D01*
X53107Y340995D01*
X53060Y340907D01*
X53019Y340807D01*
X52996Y340696D01*
X52984Y340573D01*
Y340537D01*
X52990Y340514D01*
X52996Y340449D01*
X53014Y340373D01*
X53043Y340279D01*
X53084Y340185D01*
X53143Y340091D01*
X53225Y340003D01*
X53236Y339992D01*
X53272Y339968D01*
X53324Y339933D01*
X53401Y339886D01*
X53495Y339845D01*
X53606Y339810D01*
X53741Y339786D01*
X53894Y339775D01*
X53899D01*
X53911D01*
X53935D01*
X53964Y339781D01*
X54005D01*
X54046Y339786D01*
X54140Y339804D01*
X54252Y339827D01*
X54369Y339869D01*
X54480Y339927D01*
X54580Y340003D01*
X54586D01*
X54592Y340015D01*
X54621Y340045D01*
X54662Y340091D01*
X54709Y340156D01*
X54750Y340238D01*
X54791Y340332D01*
X54821Y340438D01*
X54832Y340496D01*
Y340590D01*
X54827Y340614D01*
X54821Y340678D01*
X54797Y340755D01*
X54768Y340848D01*
X54715Y340948D01*
X54651Y341048D01*
X54604Y341095D01*
X54557Y341142D01*
X54551D01*
X54545Y341153D01*
X54527Y341165D01*
X54510Y341177D01*
X54451Y341218D01*
X54369Y341259D01*
X54269Y341306D01*
X54146Y341347D01*
X54005Y341371D01*
X53853Y341382D01*
D02*
G37*
G36*
X25545Y143578D02*
X24266D01*
Y142235D01*
X25475D01*
X25545Y142241D01*
X25627Y142246D01*
X25721Y142252D01*
X25815Y142264D01*
X25909Y142282D01*
X25991Y142305D01*
X26003Y142311D01*
X26026Y142323D01*
X26061Y142340D01*
X26108Y142364D01*
X26161Y142399D01*
X26214Y142440D01*
X26267Y142493D01*
X26308Y142551D01*
X26314Y142557D01*
X26325Y142581D01*
X26343Y142616D01*
X26366Y142663D01*
X26384Y142716D01*
X26402Y142774D01*
X26413Y142845D01*
X26419Y142915D01*
Y142921D01*
Y142927D01*
X26413Y142962D01*
X26407Y143015D01*
X26396Y143085D01*
X26366Y143156D01*
X26331Y143238D01*
X26278Y143314D01*
X26208Y143391D01*
X26196Y143396D01*
X26167Y143420D01*
X26120Y143449D01*
X26044Y143484D01*
X25956Y143520D01*
X25838Y143549D01*
X25703Y143573D01*
X25545Y143578D01*
D02*
G37*
G36*
X95617Y340588D02*
X95606D01*
X95582D01*
X95541D01*
X95488Y340582D01*
X95424Y340576D01*
X95347Y340564D01*
X95259Y340552D01*
X95171Y340541D01*
X94972Y340494D01*
X94872Y340464D01*
X94773Y340423D01*
X94673Y340382D01*
X94579Y340329D01*
X94485Y340271D01*
X94403Y340200D01*
X94397Y340194D01*
X94385Y340183D01*
X94362Y340159D01*
X94338Y340130D01*
X94303Y340089D01*
X94268Y340042D01*
X94233Y339989D01*
X94192Y339925D01*
X94150Y339860D01*
X94115Y339784D01*
X94080Y339701D01*
X94045Y339613D01*
X94021Y339514D01*
X93998Y339414D01*
X93986Y339308D01*
X93980Y339197D01*
Y339144D01*
X93986Y339091D01*
X93992Y339021D01*
X94004Y338933D01*
X94027Y338845D01*
X94051Y338745D01*
X94086Y338651D01*
X94092Y338663D01*
X94115Y338692D01*
X94145Y338745D01*
X94180Y338810D01*
X94215Y338892D01*
X94256Y338980D01*
X94291Y339080D01*
X94321Y339185D01*
X94708Y339050D01*
Y339044D01*
X94702Y339027D01*
X94696Y339003D01*
X94684Y338974D01*
X94673Y338933D01*
X94655Y338886D01*
X94614Y338780D01*
X94555Y338657D01*
X94491Y338528D01*
X94415Y338405D01*
X94321Y338282D01*
X94326Y338276D01*
X94338Y338258D01*
X94368Y338235D01*
X94403Y338205D01*
X94450Y338170D01*
X94503Y338129D01*
X94567Y338088D01*
X94643Y338041D01*
X94731Y338000D01*
X94831Y337959D01*
X94937Y337918D01*
X95048Y337883D01*
X95177Y337847D01*
X95312Y337824D01*
X95459Y337812D01*
X95617Y337806D01*
X95623D01*
X95641D01*
X95664D01*
X95700D01*
X95746Y337812D01*
X95793D01*
X95852Y337818D01*
X95911Y337830D01*
X96046Y337847D01*
X96192Y337877D01*
X96339Y337918D01*
X96480Y337976D01*
X96486D01*
X96497Y337982D01*
X96515Y337994D01*
X96538Y338006D01*
X96609Y338047D01*
X96691Y338100D01*
X96785Y338170D01*
X96879Y338258D01*
X96973Y338358D01*
X97055Y338469D01*
Y338475D01*
X97067Y338481D01*
X97072Y338499D01*
X97090Y338528D01*
X97102Y338557D01*
X97119Y338593D01*
X97161Y338681D01*
X97196Y338786D01*
X97231Y338909D01*
X97254Y339050D01*
X97260Y339197D01*
Y339256D01*
X97254Y339297D01*
X97248Y339350D01*
X97237Y339408D01*
X97225Y339473D01*
X97207Y339543D01*
X97184Y339625D01*
X97161Y339701D01*
X97125Y339784D01*
X97084Y339872D01*
X97037Y339954D01*
X96979Y340036D01*
X96920Y340118D01*
X96844Y340194D01*
X96838Y340200D01*
X96826Y340212D01*
X96803Y340230D01*
X96767Y340253D01*
X96726Y340288D01*
X96673Y340318D01*
X96609Y340353D01*
X96538Y340388D01*
X96456Y340429D01*
X96362Y340464D01*
X96263Y340494D01*
X96151Y340523D01*
X96034Y340552D01*
X95905Y340570D01*
X95764Y340582D01*
X95617Y340588D01*
D02*
G37*
G36*
X84472Y385605D02*
X83193D01*
Y384261D01*
X84402D01*
X84472Y384267D01*
X84555Y384273D01*
X84648Y384279D01*
X84742Y384290D01*
X84836Y384308D01*
X84918Y384332D01*
X84930Y384337D01*
X84953Y384349D01*
X84989Y384367D01*
X85036Y384390D01*
X85089Y384425D01*
X85141Y384467D01*
X85194Y384519D01*
X85235Y384578D01*
X85241Y384584D01*
X85253Y384607D01*
X85270Y384642D01*
X85294Y384689D01*
X85311Y384742D01*
X85329Y384801D01*
X85341Y384871D01*
X85347Y384942D01*
Y384948D01*
Y384953D01*
X85341Y384989D01*
X85335Y385042D01*
X85323Y385112D01*
X85294Y385182D01*
X85259Y385264D01*
X85206Y385341D01*
X85135Y385417D01*
X85124Y385423D01*
X85094Y385446D01*
X85047Y385476D01*
X84971Y385511D01*
X84883Y385546D01*
X84766Y385575D01*
X84631Y385599D01*
X84472Y385605D01*
D02*
G37*
G36*
X91014Y385663D02*
X90979D01*
X90956Y385658D01*
X90891Y385646D01*
X90815Y385628D01*
X90727Y385593D01*
X90633Y385540D01*
X90586Y385505D01*
X90539Y385470D01*
X90498Y385423D01*
X90457Y385370D01*
Y385364D01*
X90445Y385352D01*
X90434Y385329D01*
X90416Y385300D01*
X90399Y385253D01*
X90375Y385200D01*
X90357Y385135D01*
X90334Y385059D01*
X90310Y384971D01*
X90287Y384871D01*
X90264Y384760D01*
X90246Y384637D01*
X90228Y384496D01*
X90217Y384343D01*
X90211Y384179D01*
X90205Y383997D01*
Y383985D01*
Y383956D01*
Y383903D01*
X90211Y383833D01*
Y383756D01*
X90217Y383663D01*
X90223Y383563D01*
X90234Y383457D01*
X90264Y383228D01*
X90281Y383117D01*
X90305Y383011D01*
X90328Y382912D01*
X90363Y382818D01*
X90399Y382736D01*
X90440Y382665D01*
Y382659D01*
X90451Y382653D01*
X90481Y382612D01*
X90533Y382560D01*
X90598Y382501D01*
X90686Y382442D01*
X90786Y382389D01*
X90897Y382348D01*
X90956Y382342D01*
X91020Y382337D01*
X91056D01*
X91079Y382342D01*
X91138Y382354D01*
X91220Y382378D01*
X91308Y382419D01*
X91408Y382477D01*
X91455Y382513D01*
X91502Y382560D01*
X91549Y382607D01*
X91595Y382665D01*
Y382671D01*
X91607Y382683D01*
X91619Y382700D01*
X91631Y382730D01*
X91654Y382771D01*
X91672Y382824D01*
X91695Y382882D01*
X91719Y382953D01*
X91736Y383041D01*
X91760Y383135D01*
X91783Y383246D01*
X91801Y383363D01*
X91812Y383504D01*
X91824Y383651D01*
X91836Y383815D01*
Y383997D01*
Y384003D01*
Y384009D01*
Y384038D01*
Y384091D01*
X91830Y384161D01*
Y384238D01*
X91824Y384332D01*
X91818Y384431D01*
X91807Y384543D01*
X91777Y384766D01*
X91760Y384877D01*
X91736Y384983D01*
X91713Y385083D01*
X91678Y385176D01*
X91642Y385259D01*
X91601Y385329D01*
Y385335D01*
X91590Y385341D01*
X91578Y385358D01*
X91560Y385382D01*
X91507Y385435D01*
X91443Y385499D01*
X91355Y385558D01*
X91255Y385611D01*
X91202Y385634D01*
X91144Y385652D01*
X91079Y385658D01*
X91014Y385663D01*
D02*
G37*
G36*
X149215Y99220D02*
X147936Y97402D01*
X149215D01*
Y99220D01*
D02*
G37*
G36*
X145554Y99578D02*
X144275D01*
Y98235D01*
X145483D01*
X145554Y98241D01*
X145636Y98246D01*
X145730Y98252D01*
X145824Y98264D01*
X145918Y98282D01*
X146000Y98305D01*
X146011Y98311D01*
X146035Y98323D01*
X146070Y98340D01*
X146117Y98364D01*
X146170Y98399D01*
X146223Y98440D01*
X146275Y98493D01*
X146316Y98552D01*
X146322Y98557D01*
X146334Y98581D01*
X146352Y98616D01*
X146375Y98663D01*
X146393Y98716D01*
X146410Y98774D01*
X146422Y98845D01*
X146428Y98915D01*
Y98921D01*
Y98927D01*
X146422Y98962D01*
X146416Y99015D01*
X146404Y99086D01*
X146375Y99156D01*
X146340Y99238D01*
X146287Y99314D01*
X146217Y99391D01*
X146205Y99396D01*
X146176Y99420D01*
X146129Y99449D01*
X146052Y99485D01*
X145964Y99520D01*
X145847Y99549D01*
X145712Y99572D01*
X145554Y99578D01*
D02*
G37*
G36*
X56545Y101605D02*
X55266D01*
Y100261D01*
X56474D01*
X56545Y100267D01*
X56627Y100273D01*
X56721Y100279D01*
X56815Y100290D01*
X56909Y100308D01*
X56991Y100331D01*
X57003Y100337D01*
X57026Y100349D01*
X57061Y100367D01*
X57108Y100390D01*
X57161Y100425D01*
X57214Y100466D01*
X57267Y100519D01*
X57308Y100578D01*
X57313Y100584D01*
X57325Y100607D01*
X57343Y100642D01*
X57366Y100689D01*
X57384Y100742D01*
X57401Y100801D01*
X57413Y100871D01*
X57419Y100942D01*
Y100948D01*
Y100954D01*
X57413Y100989D01*
X57407Y101041D01*
X57396Y101112D01*
X57366Y101182D01*
X57331Y101264D01*
X57278Y101341D01*
X57208Y101417D01*
X57196Y101423D01*
X57167Y101446D01*
X57120Y101476D01*
X57044Y101511D01*
X56956Y101546D01*
X56838Y101575D01*
X56703Y101599D01*
X56545Y101605D01*
D02*
G37*
G36*
X61938Y153569D02*
X60659D01*
Y152226D01*
X61868D01*
X61938Y152232D01*
X62020Y152238D01*
X62114Y152243D01*
X62208Y152255D01*
X62302Y152273D01*
X62384Y152296D01*
X62396Y152302D01*
X62419Y152314D01*
X62454Y152331D01*
X62501Y152355D01*
X62554Y152390D01*
X62607Y152431D01*
X62660Y152484D01*
X62701Y152543D01*
X62707Y152549D01*
X62718Y152572D01*
X62736Y152607D01*
X62759Y152654D01*
X62777Y152707D01*
X62795Y152766D01*
X62806Y152836D01*
X62812Y152907D01*
Y152912D01*
Y152918D01*
X62806Y152954D01*
X62800Y153006D01*
X62789Y153077D01*
X62759Y153147D01*
X62724Y153229D01*
X62671Y153306D01*
X62601Y153382D01*
X62589Y153388D01*
X62560Y153411D01*
X62513Y153441D01*
X62437Y153476D01*
X62349Y153511D01*
X62231Y153540D01*
X62096Y153564D01*
X61938Y153569D01*
D02*
G37*
G36*
X147144Y141220D02*
X145865Y139402D01*
X147144D01*
Y141220D01*
D02*
G37*
%LPD*%
D10*
X187762Y344000D02*
G03*
X187762Y344000I-762J0D01*
G01*
D11*
X175338Y84000D02*
G03*
X175338Y84000I-1250J0D01*
G01*
X9628Y117328D02*
G03*
X9628Y117328I-1250J0D01*
G01*
X56689Y366770D02*
G03*
X56689Y366770I-1250J0D01*
G01*
X38250Y385480D02*
G03*
X38250Y385480I-1250J0D01*
G01*
X36750Y392000D02*
G03*
X36750Y392000I-1250J0D01*
G01*
X147054Y404624D02*
G03*
X147054Y404624I-1250J0D01*
G01*
D12*
X103638Y148250D02*
X116362D01*
X103638Y161750D02*
X116362D01*
X211000Y60015D02*
Y67985D01*
X193000Y60015D02*
Y67985D01*
X175500Y89250D02*
X192500D01*
X175500Y104750D02*
X192500D01*
X16878Y109578D02*
X33879D01*
X16878Y125078D02*
X33879D01*
X74350Y366600D02*
X82500D01*
Y360000D02*
Y366600D01*
X74350Y337400D02*
X82500D01*
Y344000D01*
X96000Y357250D02*
Y366750D01*
X144000Y357250D02*
Y366750D01*
X57638Y133750D02*
X70362D01*
X57638Y120250D02*
X70362D01*
X81660Y148476D02*
X94385D01*
X81660Y161976D02*
X94385D01*
X19638Y403138D02*
X34362D01*
X19638Y416862D02*
X34362D01*
X40000Y393730D02*
Y399730D01*
X62000Y393730D02*
Y399730D01*
X40000Y393730D02*
X62000D01*
X40000Y399730D02*
X62000D01*
X10500Y368000D02*
Y384000D01*
X31500Y368000D02*
Y384000D01*
X10500Y368000D02*
X31500D01*
X10500Y384000D02*
X31500D01*
X165804Y417624D02*
X176804D01*
X154500Y90000D02*
X165500D01*
X154500Y104000D02*
X165500D01*
X21500Y138000D02*
X32500D01*
X21500Y124000D02*
X32500D01*
X58500Y147000D02*
X69500D01*
X58500Y133000D02*
X69500D01*
X21015Y59000D02*
X28985D01*
X21015Y77000D02*
X28985D01*
D13*
X158116Y345703D02*
X159174Y346761D01*
Y348877D01*
X158116Y349935D01*
X153884D01*
X152826Y348877D01*
Y346761D01*
X153884Y345703D01*
X152826Y343587D02*
Y341471D01*
Y342529D01*
X159174D01*
X158116Y343587D01*
X152826Y334065D02*
Y338297D01*
X157058Y334065D01*
X158116D01*
X159174Y335123D01*
Y337239D01*
X158116Y338297D01*
M02*
